FILE_TYPE = MACRO_DRAWING;
SET COLOR_WIRE YELLOW;
SET COLOR_PROP ORANGE;
SET COLOR_DOT WHITE;
SET COLOR_ARC YELLOW;
SET COLOR_BODY GREEN;
SET COLOR_NOTE PURPLE;
SET PROP_DISPLAY VALUE;
SET PAGE_NUMBER P174;
FORCEADD OFFPAGE..5
(-425 2625);
FORCEPROP 2 LAST $XR1 252 
J 0
(-830 2625);
DISPLAY 0.638298 (-830 2625);
PAINT MONO (-830 2625);
FORCEPROP 2 LAST $XR0 223 
J 0
(-710 2625);
DISPLAY 0.638298 (-710 2625);
PAINT MONO (-710 2625);
FORCEPROP 2 LAST CDS_LIB standard
J 0
(-425 2625);
PAINT MONO (-425 2625);
DISPLAY INVISIBLE (-425 2625);
FORCEPROP 2 LAST PATH I10
J 0
(-375 2700);
DISPLAY 1.021277 (-375 2700);
DISPLAY INVISIBLE (-375 2700);
FORCEPROP 1 LAST OFFPAGE TRUE
J 0
(-100 2500);
DISPLAY 0.872340 (-100 2500);
DISPLAY INVISIBLE (-100 2500);
FORCEPROP 1 LAST COMMENT_BODY TRUE
J 0
(-325 2550);
DISPLAY 1.170213 (-325 2550);
PAINT GREEN (-325 2550);
DISPLAY INVISIBLE (-325 2550);
FORCEADD OFFPAGE..5
(-425 2575);
FORCEPROP 2 LAST $XR1 252 
J 0
(-830 2575);
DISPLAY 0.638298 (-830 2575);
PAINT MONO (-830 2575);
FORCEPROP 2 LAST $XR0 223 
J 0
(-710 2575);
DISPLAY 0.638298 (-710 2575);
PAINT MONO (-710 2575);
FORCEPROP 2 LAST PATH I11
J 0
(-375 2650);
DISPLAY 1.021277 (-375 2650);
DISPLAY INVISIBLE (-375 2650);
FORCEPROP 1 LAST COMMENT_BODY TRUE
J 0
(-325 2500);
DISPLAY 1.170213 (-325 2500);
PAINT GREEN (-325 2500);
DISPLAY INVISIBLE (-325 2500);
FORCEPROP 1 LAST OFFPAGE TRUE
J 0
(-100 2450);
DISPLAY 0.872340 (-100 2450);
DISPLAY INVISIBLE (-100 2450);
FORCEPROP 2 LAST CDS_LIB standard
J 0
(-425 2575);
PAINT MONO (-425 2575);
DISPLAY INVISIBLE (-425 2575);
FORCEADD OFFPAGE..1
(-425 2525);
FORCEPROP 2 LAST $XR1 220 
J 0
(-827 2525);
DISPLAY 0.638298 (-827 2525);
PAINT MONO (-827 2525);
FORCEPROP 2 LAST $XR0 223 
J 0
(-707 2525);
DISPLAY 0.638298 (-707 2525);
PAINT MONO (-707 2525);
FORCEPROP 2 LAST CDS_LIB standard
J 0
(-425 2525);
PAINT MONO (-425 2525);
DISPLAY INVISIBLE (-425 2525);
FORCEPROP 2 LAST PATH I12
J 0
(-375 2600);
DISPLAY 1.021277 (-375 2600);
DISPLAY INVISIBLE (-375 2600);
FORCEPROP 1 LAST OFFPAGE TRUE
J 0
(-100 2400);
DISPLAY 0.872340 (-100 2400);
DISPLAY INVISIBLE (-100 2400);
FORCEPROP 1 LAST COMMENT_BODY TRUE
J 0
(-300 2425);
DISPLAY 1.170213 (-300 2425);
PAINT GREEN (-300 2425);
DISPLAY INVISIBLE (-300 2425);
FORCEADD OFFPAGE..5
(-425 1825);
FORCEPROP 2 LAST $XR0 131 
J 0
(-710 1825);
DISPLAY 0.638298 (-710 1825);
PAINT MONO (-710 1825);
FORCEPROP 1 LAST COMMENT_BODY TRUE
J 0
(-325 1750);
DISPLAY 1.170213 (-325 1750);
PAINT GREEN (-325 1750);
DISPLAY INVISIBLE (-325 1750);
FORCEPROP 1 LAST OFFPAGE TRUE
J 0
(-100 1700);
DISPLAY 0.872340 (-100 1700);
DISPLAY INVISIBLE (-100 1700);
FORCEPROP 2 LAST PATH I17
J 0
(-375 1900);
DISPLAY 1.021277 (-375 1900);
DISPLAY INVISIBLE (-375 1900);
FORCEPROP 2 LAST CDS_LIB standard
J 0
(-425 1825);
DISPLAY INVISIBLE (-425 1825);
FORCEADD OFFPAGE..5
(-425 1975);
FORCEPROP 2 LAST $XR0 132 
J 0
(-710 1975);
DISPLAY 0.638298 (-710 1975);
PAINT MONO (-710 1975);
FORCEPROP 1 LAST OFFPAGE TRUE
J 0
(-100 1850);
DISPLAY 0.872340 (-100 1850);
DISPLAY INVISIBLE (-100 1850);
FORCEPROP 1 LAST COMMENT_BODY TRUE
J 0
(-325 1900);
DISPLAY 1.170213 (-325 1900);
PAINT GREEN (-325 1900);
DISPLAY INVISIBLE (-325 1900);
FORCEPROP 2 LAST CDS_LIB standard
J 0
(-425 1975);
DISPLAY INVISIBLE (-425 1975);
FORCEPROP 2 LAST PATH I19
J 0
(-375 2050);
DISPLAY 1.021277 (-375 2050);
DISPLAY INVISIBLE (-375 2050);
FORCEADD OFFPAGE..1
(-425 1925);
FORCEPROP 2 LAST $XR0 132 
J 0
(-707 1925);
DISPLAY 0.638298 (-707 1925);
PAINT MONO (-707 1925);
FORCEPROP 2 LAST CDS_LIB standard
J 0
(-425 1925);
PAINT MONO (-425 1925);
DISPLAY INVISIBLE (-425 1925);
FORCEPROP 1 LAST COMMENT_BODY TRUE
J 0
(-300 1825);
DISPLAY 1.170213 (-300 1825);
PAINT GREEN (-300 1825);
DISPLAY INVISIBLE (-300 1825);
FORCEPROP 1 LAST OFFPAGE TRUE
J 0
(-100 1800);
DISPLAY 0.872340 (-100 1800);
DISPLAY INVISIBLE (-100 1800);
FORCEPROP 2 LAST PATH I20
J 0
(-375 2000);
DISPLAY 1.021277 (-375 2000);
DISPLAY INVISIBLE (-375 2000);
FORCEADD OFFPAGE..5
(-425 2075);
FORCEPROP 2 LAST $XR3 44 
J 0
(-1010 2075);
DISPLAY 0.638298 (-1010 2075);
PAINT MONO (-1010 2075);
FORCEPROP 2 LAST $XR2 13 
J 0
(-920 2075);
DISPLAY 0.638298 (-920 2075);
PAINT MONO (-920 2075);
FORCEPROP 2 LAST $XR1 134 
J 0
(-830 2075);
DISPLAY 0.638298 (-830 2075);
PAINT MONO (-830 2075);
FORCEPROP 2 LAST $XR0 131 
J 0
(-710 2075);
DISPLAY 0.638298 (-710 2075);
PAINT MONO (-710 2075);
FORCEPROP 1 LAST COMMENT_BODY TRUE
J 0
(-325 2000);
DISPLAY 1.170213 (-325 2000);
PAINT GREEN (-325 2000);
DISPLAY INVISIBLE (-325 2000);
FORCEPROP 1 LAST OFFPAGE TRUE
J 0
(-100 1950);
DISPLAY 0.872340 (-100 1950);
DISPLAY INVISIBLE (-100 1950);
FORCEPROP 2 LAST PATH I21
J 0
(-375 2150);
DISPLAY 1.021277 (-375 2150);
DISPLAY INVISIBLE (-375 2150);
FORCEPROP 2 LAST CDS_LIB standard
J 0
(-425 2075);
DISPLAY INVISIBLE (-425 2075);
FORCEADD OFFPAGE..1
(-425 2125);
FORCEPROP 2 LAST $XR0 132 
J 0
(-707 2125);
DISPLAY 0.638298 (-707 2125);
PAINT MONO (-707 2125);
FORCEPROP 2 LAST CDS_LIB standard
J 0
(-425 2125);
PAINT MONO (-425 2125);
DISPLAY INVISIBLE (-425 2125);
FORCEPROP 1 LAST COMMENT_BODY TRUE
J 0
(-300 2025);
DISPLAY 1.170213 (-300 2025);
PAINT GREEN (-300 2025);
DISPLAY INVISIBLE (-300 2025);
FORCEPROP 1 LAST OFFPAGE TRUE
J 0
(-100 2000);
DISPLAY 0.872340 (-100 2000);
DISPLAY INVISIBLE (-100 2000);
FORCEPROP 2 LAST PATH I22
J 0
(-375 2200);
DISPLAY 1.021277 (-375 2200);
DISPLAY INVISIBLE (-375 2200);
FORCEADD OFFPAGE..5
(-425 2175);
FORCEPROP 2 LAST $XR0 132 
J 0
(-710 2175);
DISPLAY 0.638298 (-710 2175);
PAINT MONO (-710 2175);
FORCEPROP 2 LAST PATH I23
J 0
(-375 2250);
DISPLAY 1.021277 (-375 2250);
DISPLAY INVISIBLE (-375 2250);
FORCEPROP 2 LAST CDS_LIB standard
J 0
(-425 2175);
DISPLAY INVISIBLE (-425 2175);
FORCEPROP 1 LAST COMMENT_BODY TRUE
J 0
(-325 2100);
DISPLAY 1.170213 (-325 2100);
PAINT GREEN (-325 2100);
DISPLAY INVISIBLE (-325 2100);
FORCEPROP 1 LAST OFFPAGE TRUE
J 0
(-100 2050);
DISPLAY 0.872340 (-100 2050);
DISPLAY INVISIBLE (-100 2050);
FORCEADD OFFPAGE..1
(-425 2225);
FORCEPROP 2 LAST $XR0 132 
J 0
(-677 2225);
DISPLAY 0.638298 (-677 2225);
PAINT MONO (-677 2225);
FORCEPROP 2 LAST CDS_LIB standard
J 0
(-425 2225);
PAINT MONO (-425 2225);
DISPLAY INVISIBLE (-425 2225);
FORCEPROP 1 LAST COMMENT_BODY TRUE
J 0
(-300 2125);
DISPLAY 1.170213 (-300 2125);
PAINT GREEN (-300 2125);
DISPLAY INVISIBLE (-300 2125);
FORCEPROP 1 LAST OFFPAGE TRUE
J 0
(-100 2100);
DISPLAY 0.872340 (-100 2100);
DISPLAY INVISIBLE (-100 2100);
FORCEPROP 2 LAST PATH I24
J 0
(-375 2300);
DISPLAY 1.021277 (-375 2300);
DISPLAY INVISIBLE (-375 2300);
FORCEADD OFFPAGE..1
(-425 2275);
FORCEPROP 2 LAST $XR1 134 
J 0
(-797 2275);
DISPLAY 0.638298 (-797 2275);
PAINT MONO (-797 2275);
FORCEPROP 2 LAST $XR0 131 
J 0
(-677 2275);
DISPLAY 0.638298 (-677 2275);
PAINT MONO (-677 2275);
FORCEPROP 1 LAST COMMENT_BODY TRUE
J 0
(-300 2175);
DISPLAY 1.170213 (-300 2175);
PAINT GREEN (-300 2175);
DISPLAY INVISIBLE (-300 2175);
FORCEPROP 1 LAST OFFPAGE TRUE
J 0
(-100 2150);
DISPLAY 0.872340 (-100 2150);
DISPLAY INVISIBLE (-100 2150);
FORCEPROP 2 LAST PATH I25
J 0
(-375 2350);
DISPLAY 1.021277 (-375 2350);
DISPLAY INVISIBLE (-375 2350);
FORCEPROP 2 LAST CDS_LIB standard
J 0
(-425 2275);
PAINT MONO (-425 2275);
DISPLAY INVISIBLE (-425 2275);
FORCEADD OFFPAGE..1
R 2
(4200 2975);
FORCEPROP 2 LAST $XR1 225 
J 0
(4506 2975);
DISPLAY 0.638298 (4506 2975);
PAINT MONO (4506 2975);
FORCEPROP 2 LAST $XR0 204 
J 0
(4386 2975);
DISPLAY 0.638298 (4386 2975);
PAINT MONO (4386 2975);
FORCEPROP 2 LAST CDS_LIB standard
J 0
(4200 2975);
PAINT MONO (4200 2975);
DISPLAY INVISIBLE (4200 2975);
FORCEPROP 2 LAST PATH I26
J 0
(4400 3025);
DISPLAY 1.021277 (4400 3025);
DISPLAY INVISIBLE (4400 3025);
FORCEPROP 1 LAST COMMENT_BODY TRUE
J 2
(4075 2875);
DISPLAY 0.872340 (4075 2875);
PAINT GREEN (4075 2875);
DISPLAY INVISIBLE (4075 2875);
FORCEPROP 1 LAST OFFPAGE TRUE
J 2
(3875 2850);
DISPLAY 0.872340 (3875 2850);
DISPLAY INVISIBLE (3875 2850);
FORCEADD OFFPAGE..1
R 2
(4200 3025);
FORCEPROP 2 LAST $XR1 225 
J 0
(4506 3025);
DISPLAY 0.638298 (4506 3025);
PAINT MONO (4506 3025);
FORCEPROP 2 LAST $XR0 204 
J 0
(4386 3025);
DISPLAY 0.638298 (4386 3025);
PAINT MONO (4386 3025);
FORCEPROP 2 LAST CDS_LIB standard
J 0
(4200 3025);
PAINT MONO (4200 3025);
DISPLAY INVISIBLE (4200 3025);
FORCEPROP 1 LAST OFFPAGE TRUE
J 2
(3875 2900);
DISPLAY 0.872340 (3875 2900);
DISPLAY INVISIBLE (3875 2900);
FORCEPROP 1 LAST COMMENT_BODY TRUE
J 2
(4075 2925);
DISPLAY 0.872340 (4075 2925);
PAINT GREEN (4075 2925);
DISPLAY INVISIBLE (4075 2925);
FORCEPROP 2 LAST PATH I27
J 0
(4400 3075);
DISPLAY 1.021277 (4400 3075);
DISPLAY INVISIBLE (4400 3075);
FORCEADD OFFPAGE..1
R 2
(4200 3075);
FORCEPROP 2 LAST $XR1 225 
J 0
(4506 3075);
DISPLAY 0.638298 (4506 3075);
PAINT MONO (4506 3075);
FORCEPROP 2 LAST $XR0 204 
J 0
(4386 3075);
DISPLAY 0.638298 (4386 3075);
PAINT MONO (4386 3075);
FORCEPROP 1 LAST COMMENT_BODY TRUE
J 2
(4075 2975);
DISPLAY 0.872340 (4075 2975);
PAINT GREEN (4075 2975);
DISPLAY INVISIBLE (4075 2975);
FORCEPROP 1 LAST OFFPAGE TRUE
J 2
(3875 2950);
DISPLAY 0.872340 (3875 2950);
DISPLAY INVISIBLE (3875 2950);
FORCEPROP 2 LAST CDS_LIB standard
J 0
(4200 3075);
PAINT MONO (4200 3075);
DISPLAY INVISIBLE (4200 3075);
FORCEPROP 2 LAST PATH I28
J 0
(4400 3125);
DISPLAY 1.021277 (4400 3125);
DISPLAY INVISIBLE (4400 3125);
FORCEADD OFFPAGE..2
(4200 2925);
FORCEPROP 2 LAST $XR0 197 
J 0
(4389 2925);
DISPLAY 0.638298 (4389 2925);
PAINT MONO (4389 2925);
FORCEPROP 2 LAST CDS_LIB standard
J 0
(4200 2925);
PAINT MONO (4200 2925);
DISPLAY INVISIBLE (4200 2925);
FORCEPROP 2 LAST PATH I29
J 0
(4375 3000);
DISPLAY 1.021277 (4375 3000);
DISPLAY INVISIBLE (4375 3000);
FORCEPROP 1 LAST COMMENT_BODY TRUE
J 0
(4155 2830);
DISPLAY 0.872340 (4155 2830);
PAINT GREEN (4155 2830);
DISPLAY INVISIBLE (4155 2830);
FORCEPROP 1 LAST OFFPAGE TRUE
J 0
(4525 2800);
DISPLAY 0.872340 (4525 2800);
PAINT GREEN (4525 2800);
DISPLAY INVISIBLE (4525 2800);
FORCEADD OFFPAGE..1
(-425 3075);
FORCEPROP 2 LAST $XR2 190 
J 0
(-947 3075);
DISPLAY 0.638298 (-947 3075);
PAINT MONO (-947 3075);
FORCEPROP 2 LAST $XR1 161 
J 0
(-827 3075);
DISPLAY 0.638298 (-827 3075);
PAINT MONO (-827 3075);
FORCEPROP 2 LAST $XR0 155 
J 0
(-707 3075);
DISPLAY 0.638298 (-707 3075);
PAINT MONO (-707 3075);
FORCEPROP 1 LAST COMMENT_BODY TRUE
J 0
(-300 2975);
DISPLAY 1.170213 (-300 2975);
PAINT GREEN (-300 2975);
DISPLAY INVISIBLE (-300 2975);
FORCEPROP 1 LAST OFFPAGE TRUE
J 0
(-100 2950);
DISPLAY 0.872340 (-100 2950);
DISPLAY INVISIBLE (-100 2950);
FORCEPROP 2 LAST PATH I3
J 0
(-725 3125);
DISPLAY 1.021277 (-725 3125);
DISPLAY INVISIBLE (-725 3125);
FORCEPROP 2 LAST CDS_LIB standard
J 0
(-425 3075);
PAINT MONO (-425 3075);
DISPLAY INVISIBLE (-425 3075);
FORCEADD OFFPAGE..1
R 2
(4200 2275);
FORCEPROP 2 LAST $XR3 214 
J 0
(4746 2275);
DISPLAY 0.638298 (4746 2275);
PAINT MONO (4746 2275);
FORCEPROP 2 LAST $XR2 307 
J 0
(4626 2275);
DISPLAY 0.638298 (4626 2275);
PAINT MONO (4626 2275);
FORCEPROP 2 LAST $XR1 306 
J 0
(4506 2275);
DISPLAY 0.638298 (4506 2275);
PAINT MONO (4506 2275);
FORCEPROP 2 LAST $XR0 244 
J 0
(4386 2275);
DISPLAY 0.638298 (4386 2275);
PAINT MONO (4386 2275);
FORCEPROP 1 LAST OFFPAGE TRUE
J 2
(3875 2150);
DISPLAY 0.872340 (3875 2150);
DISPLAY INVISIBLE (3875 2150);
FORCEPROP 1 LAST COMMENT_BODY TRUE
J 2
(4075 2175);
DISPLAY 0.872340 (4075 2175);
PAINT GREEN (4075 2175);
DISPLAY INVISIBLE (4075 2175);
FORCEPROP 2 LAST PATH I31
J 0
(4400 2325);
DISPLAY 1.021277 (4400 2325);
DISPLAY INVISIBLE (4400 2325);
FORCEPROP 2 LAST CDS_LIB standard
J 0
(4200 2275);
PAINT MONO (4200 2275);
DISPLAY INVISIBLE (4200 2275);
FORCEADD OFFPAGE..1
R 2
(4200 2325);
FORCEPROP 2 LAST $XR1 219 
J 0
(4506 2325);
DISPLAY 0.638298 (4506 2325);
PAINT MONO (4506 2325);
FORCEPROP 2 LAST $XR0 222 
J 0
(4386 2325);
DISPLAY 0.638298 (4386 2325);
PAINT MONO (4386 2325);
FORCEPROP 1 LAST COMMENT_BODY TRUE
J 2
(4075 2225);
DISPLAY 0.872340 (4075 2225);
PAINT GREEN (4075 2225);
DISPLAY INVISIBLE (4075 2225);
FORCEPROP 1 LAST OFFPAGE TRUE
J 2
(3875 2200);
DISPLAY 0.872340 (3875 2200);
DISPLAY INVISIBLE (3875 2200);
FORCEPROP 2 LAST PATH I32
J 0
(4400 2375);
DISPLAY 1.021277 (4400 2375);
DISPLAY INVISIBLE (4400 2375);
FORCEPROP 2 LAST CDS_LIB standard
J 0
(4200 2325);
PAINT MONO (4200 2325);
DISPLAY INVISIBLE (4200 2325);
FORCEADD OFFPAGE..1
R 2
(4200 2375);
FORCEPROP 2 LAST $XR2 131 
J 0
(4626 2375);
DISPLAY 0.638298 (4626 2375);
PAINT MONO (4626 2375);
FORCEPROP 2 LAST $XR1 244 
J 0
(4506 2375);
DISPLAY 0.638298 (4506 2375);
PAINT MONO (4506 2375);
FORCEPROP 2 LAST $XR0 223 
J 0
(4386 2375);
DISPLAY 0.638298 (4386 2375);
PAINT MONO (4386 2375);
FORCEPROP 1 LAST OFFPAGE TRUE
J 2
(3875 2250);
DISPLAY 0.872340 (3875 2250);
DISPLAY INVISIBLE (3875 2250);
FORCEPROP 1 LAST COMMENT_BODY TRUE
J 2
(4075 2275);
DISPLAY 0.872340 (4075 2275);
PAINT GREEN (4075 2275);
DISPLAY INVISIBLE (4075 2275);
FORCEPROP 2 LAST PATH I33
J 0
(4400 2425);
DISPLAY 1.021277 (4400 2425);
DISPLAY INVISIBLE (4400 2425);
FORCEPROP 2 LAST CDS_LIB standard
J 0
(4200 2375);
PAINT MONO (4200 2375);
DISPLAY INVISIBLE (4200 2375);
FORCEADD OFFPAGE..2
(4200 2475);
FORCEPROP 2 LAST $XR0 118 
J 0
(4389 2475);
DISPLAY 0.638298 (4389 2475);
PAINT MONO (4389 2475);
FORCEPROP 1 LAST OFFPAGE TRUE
J 0
(4525 2350);
DISPLAY 0.872340 (4525 2350);
PAINT GREEN (4525 2350);
DISPLAY INVISIBLE (4525 2350);
FORCEPROP 1 LAST COMMENT_BODY TRUE
J 0
(4155 2380);
DISPLAY 0.872340 (4155 2380);
PAINT GREEN (4155 2380);
DISPLAY INVISIBLE (4155 2380);
FORCEPROP 2 LAST PATH I34
J 0
(4375 2550);
DISPLAY 1.021277 (4375 2550);
DISPLAY INVISIBLE (4375 2550);
FORCEPROP 2 LAST CDS_LIB standard
J 0
(4200 2475);
PAINT MONO (4200 2475);
DISPLAY INVISIBLE (4200 2475);
FORCEADD OFFPAGE..2
(4200 2725);
FORCEPROP 2 LAST $XR0 203 
J 0
(4389 2725);
DISPLAY 0.638298 (4389 2725);
PAINT MONO (4389 2725);
FORCEPROP 1 LAST OFFPAGE TRUE
J 0
(4525 2600);
DISPLAY 0.872340 (4525 2600);
PAINT GREEN (4525 2600);
DISPLAY INVISIBLE (4525 2600);
FORCEPROP 1 LAST COMMENT_BODY TRUE
J 0
(4155 2630);
DISPLAY 0.872340 (4155 2630);
PAINT GREEN (4155 2630);
DISPLAY INVISIBLE (4155 2630);
FORCEPROP 2 LAST PATH I35
J 0
(4375 2800);
DISPLAY 1.021277 (4375 2800);
DISPLAY INVISIBLE (4375 2800);
FORCEPROP 2 LAST CDS_LIB standard
J 0
(4200 2725);
PAINT MONO (4200 2725);
DISPLAY INVISIBLE (4200 2725);
FORCEADD EMMITSBURG_REV0P9..4
(2000 2475);
FORCEPROP 1 LAST PART_NUMBER AJ0QV2N0T00
J 0
(1035 3383);
DISPLAY 0.723404 (1035 3383);
PAINT GREEN (1035 3383);
DISPLAY INVISIBLE (1035 3383);
FORCEPROP 2 LAST PART_TYPE SMLF
J 0
(1050 3575);
DISPLAY 1.021277 (1050 3575);
FORCEPROP 1 LAST MATERIAL IC
J 0
(1035 3296);
DISPLAY 0.723404 (1035 3296);
PAINT GREEN (1035 3296);
FORCEPROP 2 LAST VALUE GFNOCPU04302300-QV2N-MM#99A1WT
J 0
(1050 3525);
DISPLAY 1.021277 (1050 3525);
FORCEPROP 1 LAST $LOCATION U4
J 0
(1035 3490);
DISPLAY 0.723404 (1035 3490);
PAINT GREEN (1035 3490);
FORCEPROP 2 LASTPIN (875 2425) $PN AN7
J 2
(865 2435);
DISPLAY 0.808511 (865 2435);
FORCEPROP 2 LASTPIN (3125 3125) $PN F8
J 0
(3135 3135);
DISPLAY 0.808511 (3135 3135);
FORCEPROP 2 LASTPIN (3125 2975) $PN J7
J 0
(3135 2985);
DISPLAY 0.808511 (3135 2985);
FORCEPROP 2 LASTPIN (3125 3025) $PN G7
J 0
(3135 3035);
DISPLAY 0.808511 (3135 3035);
FORCEPROP 2 LASTPIN (3125 3075) $PN L7
J 0
(3135 3085);
DISPLAY 0.808511 (3135 3085);
FORCEPROP 2 LASTPIN (3125 2775) $PN E4
J 0
(3135 2785);
DISPLAY 0.808511 (3135 2785);
FORCEPROP 2 LASTPIN (3125 2825) $PN F11
J 0
(3135 2835);
DISPLAY 0.808511 (3135 2835);
FORCEPROP 2 LASTPIN (3125 2725) $PN F5
J 0
(3135 2735);
DISPLAY 0.808511 (3135 2735);
FORCEPROP 2 LASTPIN (3125 2525) $PN F3
J 0
(3135 2535);
DISPLAY 0.808511 (3135 2535);
FORCEPROP 2 LASTPIN (3125 2475) $PN G10
J 0
(3135 2485);
DISPLAY 0.808511 (3135 2485);
FORCEPROP 2 LASTPIN (875 1825) $PN BE40
J 2
(865 1835);
DISPLAY 0.808511 (865 1835);
FORCEPROP 2 LASTPIN (3125 2275) $PN BE8
J 0
(3135 2285);
DISPLAY 0.808511 (3135 2285);
FORCEPROP 2 LASTPIN (875 2375) $PN AN10
J 2
(865 2385);
DISPLAY 0.808511 (865 2385);
FORCEPROP 2 LASTPIN (875 2725) $PN AU10
J 2
(865 2735);
DISPLAY 0.808511 (865 2735);
FORCEPROP 2 LASTPIN (3125 2225) $PN BG8
J 0
(3135 2235);
DISPLAY 0.808511 (3135 2235);
FORCEPROP 2 LASTPIN (875 2275) $PN BF35
J 2
(865 2285);
DISPLAY 0.808511 (865 2285);
FORCEPROP 2 LASTPIN (875 2225) $PN BE38
J 2
(865 2235);
DISPLAY 0.808511 (865 2235);
FORCEPROP 2 LASTPIN (875 2175) $PN BE36
J 2
(865 2185);
DISPLAY 0.808511 (865 2185);
FORCEPROP 2 LASTPIN (875 2125) $PN BD37
J 2
(865 2135);
DISPLAY 0.808511 (865 2135);
FORCEPROP 2 LASTPIN (875 2075) $PN BD35
J 2
(865 2085);
DISPLAY 0.808511 (865 2085);
FORCEPROP 2 LASTPIN (875 2475) $PN AU7
J 2
(865 2485);
DISPLAY 0.808511 (865 2485);
FORCEPROP 2 LASTPIN (875 2875) $PN AJ7
J 2
(865 2885);
DISPLAY 0.808511 (865 2885);
FORCEPROP 2 LASTPIN (3125 2925) $PN J10
J 0
(3135 2935);
DISPLAY 0.808511 (3135 2935);
FORCEPROP 2 LASTPIN (3125 2325) $PN BE4
J 0
(3135 2335);
DISPLAY 0.808511 (3135 2335);
FORCEPROP 2 LASTPIN (3125 2575) $PN M8
J 0
(3135 2585);
DISPLAY 0.808511 (3135 2585);
FORCEPROP 2 LASTPIN (875 1925) $PN BB37
J 2
(865 1935);
DISPLAY 0.808511 (865 1935);
FORCEPROP 2 LASTPIN (875 1975) $PN BF37
J 2
(865 1985);
DISPLAY 0.808511 (865 1985);
FORCEPROP 2 LASTPIN (875 2525) $PN AR10
J 2
(865 2535);
DISPLAY 0.808511 (865 2535);
FORCEPROP 2 LASTPIN (3125 2375) $PN BD9
J 0
(3135 2385);
DISPLAY 0.808511 (3135 2385);
FORCEPROP 2 LASTPIN (3125 2075) $PN AV21
J 0
(3135 2085);
DISPLAY 0.808511 (3135 2085);
FORCEPROP 2 LASTPIN (3125 2125) $PN AW26
J 0
(3135 2135);
DISPLAY 0.808511 (3135 2135);
FORCEPROP 2 LASTPIN (3125 1975) $PN BF39
J 0
(3135 1985);
DISPLAY 0.808511 (3135 1985);
FORCEPROP 2 LASTPIN (3125 1925) $PN BG36
J 0
(3135 1935);
DISPLAY 0.808511 (3135 1935);
FORCEPROP 2 LASTPIN (875 2675) $PN AM11
J 2
(865 2685);
DISPLAY 0.808511 (865 2685);
FORCEPROP 2 LASTPIN (875 3025) $PN AK8
J 2
(865 3035);
DISPLAY 0.808511 (865 3035);
FORCEPROP 2 LASTPIN (875 2575) $PN AP8
J 2
(865 2585);
DISPLAY 0.808511 (865 2585);
FORCEPROP 2 LASTPIN (875 2625) $PN AL13
J 2
(865 2635);
DISPLAY 0.808511 (865 2635);
FORCEPROP 2 LASTPIN (875 2825) $PN AJ13
J 2
(865 2835);
DISPLAY 0.808511 (865 2835);
FORCEPROP 2 LASTPIN (875 3125) $PN AL7
J 2
(865 3135);
DISPLAY 0.808511 (865 3135);
FORCEPROP 2 LASTPIN (875 2775) $PN AR7
J 2
(865 2785);
DISPLAY 0.808511 (865 2785);
FORCEPROP 2 LASTPIN (875 2925) $PN AL10
J 2
(865 2935);
DISPLAY 0.808511 (865 2935);
FORCEPROP 2 LASTPIN (875 2975) $PN AJ10
J 2
(865 2985);
DISPLAY 0.808511 (865 2985);
FORCEPROP 2 LASTPIN (3125 2625) $PN H11
J 0
(3135 2635);
DISPLAY 0.808511 (3135 2635);
FORCEPROP 2 LASTPIN (3125 2675) $PN K8
J 0
(3135 2685);
DISPLAY 0.808511 (3135 2685);
FORCEPROP 2 LASTPIN (875 3075) $PN AH11
J 2
(865 3085);
DISPLAY 0.808511 (865 3085);
FORCEPROP 2 LAST CDS_LIB pure_quanta
J 0
(2000 2475);
PAINT MONO (2000 2475);
DISPLAY INVISIBLE (2000 2475);
FORCEPROP 1 LAST CDS_LMAN_SYM_OUTLINE -975,800,975,-800
J 0
(2000 2475);
DISPLAY 0.468085 (2000 2475);
PAINT GREEN (2000 2475);
DISPLAY INVISIBLE (2000 2475);
FORCEPROP 1 LAST PATH I36
J 0
(2000 2475);
DISPLAY 0.723404 (2000 2475);
PAINT GREEN (2000 2475);
DISPLAY INVISIBLE (2000 2475);
FORCEPROP 1 LAST NEEDS_NO_SIZE TRUE
J 0
(2000 2475);
DISPLAY 0.723404 (2000 2475);
PAINT GREEN (2000 2475);
DISPLAY INVISIBLE (2000 2475);
FORCEPROP 2 LAST CDS_LOCATION U4
J 0
(1050 3425);
DISPLAY 1.021277 (1050 3425);
DISPLAY INVISIBLE (1050 3425);
FORCEPROP 2 LAST $SEC 4
J 0
(1050 3625);
DISPLAY 0.680851 (1050 3625);
PAINT MONO (1050 3625);
DISPLAY INVISIBLE (1050 3625);
FORCEPROP 2 LAST CDS_SEC 4
J 0
(1050 3425);
DISPLAY 1.021277 (1050 3425);
DISPLAY INVISIBLE (1050 3425);
FORCEADD Q_RES..2
(525 1500);
FORCEPROP 1 LAST PART_NUMBER CS21002FB06
J 0
(565 1375);
DISPLAY 0.638298 (565 1375);
DISPLAY INVISIBLE (565 1375);
FORCEPROP 1 LAST MATERIAL CHIP
J 0
(565 1425);
DISPLAY 0.638298 (565 1425);
FORCEPROP 1 LAST WATTAGE 1/16W
J 0
(565 1475);
DISPLAY 0.638298 (565 1475);
FORCEPROP 1 LAST TOLERANCE 1%
J 0
(570 1525);
DISPLAY 0.638298 (570 1525);
FORCEPROP 1 LAST VALUE 1K
J 0
(570 1575);
DISPLAY 0.638298 (570 1575);
FORCEPROP 1 LAST PACK_TYPE 0402LF
J 0
(565 1325);
DISPLAY 0.638298 (565 1325);
FORCEPROP 1 LAST $LOCATION R1026
J 0
(570 1625);
DISPLAY 0.978723 (570 1625);
FORCEPROP 1 LASTPIN (525 1600) $PN 1
J 0
(530 1562);
DISPLAY 0.787234 (530 1562);
FORCEPROP 1 LASTPIN (525 1400) $PN 2
J 0
(530 1410);
DISPLAY 0.787234 (530 1410);
FORCEPROP 1 LAST PATH I37
J 0
(575 1675);
DISPLAY 0.978723 (575 1675);
PAINT WHITE (575 1675);
DISPLAY INVISIBLE (575 1675);
FORCEPROP 2 LAST CDS_LIB pure_quanta
J 0
(525 1500);
PAINT MONO (525 1500);
DISPLAY INVISIBLE (525 1500);
FORCEPROP 2 LAST CDS_LOCATION R1026
J 0
(575 1725);
DISPLAY 1.021277 (575 1725);
DISPLAY INVISIBLE (575 1725);
FORCEPROP 2 LAST $SEC 1
J 0
(575 1725);
DISPLAY 0.680851 (575 1725);
PAINT MONO (575 1725);
DISPLAY INVISIBLE (575 1725);
FORCEPROP 2 LAST CDS_SEC 1
J 0
(575 1725);
DISPLAY 1.021277 (575 1725);
DISPLAY INVISIBLE (575 1725);
FORCEADD Q_RES..2
(-100 1500);
FORCEPROP 1 LAST PART_NUMBER CS07502FB04
J 0
(-60 1375);
DISPLAY 0.638298 (-60 1375);
DISPLAY INVISIBLE (-60 1375);
FORCEPROP 1 LAST PACK_TYPE 0402LF
J 0
(-60 1325);
DISPLAY 0.638298 (-60 1325);
FORCEPROP 1 LAST MATERIAL EMPTY
J 0
(-60 1425);
DISPLAY 0.638298 (-60 1425);
PAINT RED (-60 1425);
FORCEPROP 1 LAST WATTAGE 1/16W
J 0
(-60 1475);
DISPLAY 0.638298 (-60 1475);
FORCEPROP 1 LAST TOLERANCE 1%
J 0
(-55 1525);
DISPLAY 0.638298 (-55 1525);
FORCEPROP 1 LAST VALUE 75
J 0
(-55 1575);
DISPLAY 0.638298 (-55 1575);
FORCEPROP 1 LAST $LOCATION R1025
J 0
(-55 1625);
DISPLAY 0.978723 (-55 1625);
FORCEPROP 1 LASTPIN (-100 1600) $PN 1
J 0
(-95 1562);
DISPLAY 0.787234 (-95 1562);
FORCEPROP 1 LASTPIN (-100 1400) $PN 2
J 0
(-95 1410);
DISPLAY 0.787234 (-95 1410);
FORCEPROP 2 LAST CDS_LIB pure_quanta
J 0
(-100 1500);
PAINT MONO (-100 1500);
DISPLAY INVISIBLE (-100 1500);
FORCEPROP 1 LAST PATH I38
J 0
(-50 1675);
DISPLAY 0.978723 (-50 1675);
PAINT WHITE (-50 1675);
DISPLAY INVISIBLE (-50 1675);
FORCEPROP 2 LAST CDS_LOCATION R1025
J 0
(-50 1725);
DISPLAY 1.021277 (-50 1725);
DISPLAY INVISIBLE (-50 1725);
FORCEPROP 2 LAST $SEC 1
J 0
(-50 1725);
DISPLAY 0.680851 (-50 1725);
PAINT MONO (-50 1725);
DISPLAY INVISIBLE (-50 1725);
FORCEPROP 2 LAST CDS_SEC 1
J 0
(-50 1725);
DISPLAY 1.021277 (-50 1725);
DISPLAY INVISIBLE (-50 1725);
FORCEADD UNIVERSAL_POWER..1
(1200 1425);
FORCEPROP 3 LASTPIN (1200 1375) SIG_NAME P1V05_PCH_AUX\g
J 0
(1210 1385);
DISPLAY 0.659574 (1210 1385);
PAINT MONO (1210 1385);
DISPLAY INVISIBLE (1210 1385);
FORCEPROP 1 LAST HDL_POWER P1V05_PCH_AUX
J 1
(1200 1475);
DISPLAY 0.872340 (1200 1475);
PAINT GREEN (1200 1475);
FORCEPROP 2 LAST CDS_LIB logical_power
J 0
(1200 1425);
PAINT MONO (1200 1425);
DISPLAY INVISIBLE (1200 1425);
FORCEPROP 1 LAST PATH I39
J 0
(1250 1450);
DISPLAY 0.872340 (1250 1450);
PAINT AQUA (1250 1450);
DISPLAY INVISIBLE (1250 1450);
FORCEADD UNIVERSAL_GND..1
(-100 1225);
FORCEPROP 3 LASTPIN (-100 1275) SIG_NAME GND\g
J 0
(-90 1285);
DISPLAY 0.659574 (-90 1285);
PAINT MONO (-90 1285);
DISPLAY INVISIBLE (-90 1285);
FORCEPROP 1 LAST HDL_POWER GND
J 1
(-75 1150);
DISPLAY 0.872340 (-75 1150);
PAINT GREEN (-75 1150);
DISPLAY INVISIBLE (-75 1150);
FORCEPROP 1 LAST PATH I40
J 0
(-25 1225);
DISPLAY 0.872340 (-25 1225);
PAINT AQUA (-25 1225);
DISPLAY INVISIBLE (-25 1225);
FORCEPROP 2 LAST CDS_LIB logical_power
J 0
(-100 1225);
PAINT MONO (-100 1225);
DISPLAY INVISIBLE (-100 1225);
FORCEADD Q_RES..2
R 2
(-250 1500);
FORCEPROP 1 LAST PART_NUMBER CS11002FB07
J 2
(-290 1375);
DISPLAY 0.638298 (-290 1375);
DISPLAY INVISIBLE (-290 1375);
FORCEPROP 1 LAST WATTAGE 1/16W
J 2
(-290 1475);
DISPLAY 0.638298 (-290 1475);
FORCEPROP 1 LAST MATERIAL CHIP
J 2
(-290 1425);
DISPLAY 0.638298 (-290 1425);
FORCEPROP 1 LAST TOLERANCE 1%
J 2
(-295 1525);
DISPLAY 0.638298 (-295 1525);
FORCEPROP 1 LAST VALUE 100
J 2
(-295 1575);
DISPLAY 0.638298 (-295 1575);
FORCEPROP 1 LAST PACK_TYPE 0402LF
J 2
(-290 1325);
DISPLAY 0.638298 (-290 1325);
FORCEPROP 1 LAST $LOCATION R1024
J 2
(-295 1625);
DISPLAY 0.978723 (-295 1625);
FORCEPROP 1 LASTPIN (-250 1600) $PN 1
J 2
(-255 1562);
DISPLAY 0.787234 (-255 1562);
FORCEPROP 1 LASTPIN (-250 1400) $PN 2
J 2
(-255 1410);
DISPLAY 0.787234 (-255 1410);
FORCEPROP 1 LAST PATH I41
J 2
(-300 1675);
DISPLAY 0.978723 (-300 1675);
PAINT WHITE (-300 1675);
DISPLAY INVISIBLE (-300 1675);
FORCEPROP 2 LAST CDS_LIB pure_quanta
J 2
(-250 1500);
PAINT MONO (-250 1500);
DISPLAY INVISIBLE (-250 1500);
FORCEPROP 2 LAST CDS_LOCATION R1024
J 0
(-300 1725);
DISPLAY 1.021277 (-300 1725);
DISPLAY INVISIBLE (-300 1725);
FORCEPROP 2 LAST $SEC 1
J 0
(-300 1725);
DISPLAY 0.680851 (-300 1725);
PAINT MONO (-300 1725);
DISPLAY INVISIBLE (-300 1725);
FORCEPROP 2 LAST CDS_SEC 1
J 0
(-300 1725);
DISPLAY 1.021277 (-300 1725);
DISPLAY INVISIBLE (-300 1725);
FORCEADD UNIVERSAL_GND..1
(-250 1225);
FORCEPROP 3 LASTPIN (-250 1275) SIG_NAME GND\g
J 0
(-240 1285);
DISPLAY 0.659574 (-240 1285);
PAINT MONO (-240 1285);
DISPLAY INVISIBLE (-240 1285);
FORCEPROP 1 LAST HDL_POWER GND
J 1
(-225 1150);
DISPLAY 0.872340 (-225 1150);
PAINT GREEN (-225 1150);
DISPLAY INVISIBLE (-225 1150);
FORCEPROP 1 LAST PATH I42
J 0
(-175 1225);
DISPLAY 0.872340 (-175 1225);
PAINT AQUA (-175 1225);
DISPLAY INVISIBLE (-175 1225);
FORCEPROP 2 LAST CDS_LIB logical_power
J 0
(-250 1225);
PAINT MONO (-250 1225);
DISPLAY INVISIBLE (-250 1225);
FORCEADD Q_RES..1
(-1850 2425);
FORCEPROP 1 LAST PART_NUMBER CS31002FB08
J 0
(-1975 2475);
DISPLAY 0.319149 (-1975 2475);
DISPLAY INVISIBLE (-1975 2475);
FORCEPROP 1 LAST MATERIAL CHIP
J 0
(-1575 2425);
DISPLAY 0.510638 (-1575 2425);
FORCEPROP 1 LAST TOLERANCE 1%
J 0
(-1650 2425);
DISPLAY 0.510638 (-1650 2425);
FORCEPROP 1 LAST WATTAGE 1/16W
J 2
(-1775 2500);
DISPLAY 0.319149 (-1775 2500);
FORCEPROP 1 LAST VALUE 10K
J 2
(-1675 2425);
DISPLAY 0.510638 (-1675 2425);
FORCEPROP 1 LAST PACK_TYPE 0402LF
J 0
(-1975 2500);
DISPLAY 0.319149 (-1975 2500);
FORCEPROP 1 LAST $LOCATION R1198
J 0
(-2075 2425);
DISPLAY 0.638298 (-2075 2425);
FORCEPROP 1 LASTPIN (-1950 2425) $PN 1
J 0
(-1938 2437);
DISPLAY 0.787234 (-1938 2437);
FORCEPROP 1 LASTPIN (-1750 2425) $PN 2
J 0
(-1788 2437);
DISPLAY 0.787234 (-1788 2437);
FORCEPROP 2 LAST CDS_LIB pure_quanta
J 0
(-1850 2425);
PAINT MONO (-1850 2425);
DISPLAY INVISIBLE (-1850 2425);
FORCEPROP 1 LAST PATH I48
J 0
(-1900 2575);
DISPLAY 0.978723 (-1900 2575);
PAINT WHITE (-1900 2575);
DISPLAY INVISIBLE (-1900 2575);
FORCEPROP 2 LAST CDS_LOCATION R1198
J 0
(-1900 2625);
DISPLAY 1.021277 (-1900 2625);
DISPLAY INVISIBLE (-1900 2625);
FORCEPROP 2 LAST $SEC 1
J 0
(-1900 2625);
DISPLAY 0.680851 (-1900 2625);
PAINT MONO (-1900 2625);
DISPLAY INVISIBLE (-1900 2625);
FORCEPROP 2 LAST CDS_SEC 1
J 0
(-1900 2625);
DISPLAY 1.021277 (-1900 2625);
DISPLAY INVISIBLE (-1900 2625);
FORCEADD UNIVERSAL_POWER..1
(-2150 2525);
FORCEPROP 3 LASTPIN (-2150 2475) SIG_NAME P3V3_AUX\g
J 0
(-2140 2485);
DISPLAY 0.659574 (-2140 2485);
PAINT MONO (-2140 2485);
DISPLAY INVISIBLE (-2140 2485);
FORCEPROP 1 LAST HDL_POWER P3V3_AUX
J 1
(-2150 2575);
DISPLAY 0.872340 (-2150 2575);
PAINT GREEN (-2150 2575);
FORCEPROP 2 LAST CDS_LIB logical_power
J 0
(-2150 2525);
PAINT MONO (-2150 2525);
DISPLAY INVISIBLE (-2150 2525);
FORCEPROP 1 LAST PATH I49
J 0
(-2100 2550);
DISPLAY 0.872340 (-2100 2550);
PAINT AQUA (-2100 2550);
DISPLAY INVISIBLE (-2100 2550);
FORCEADD UNIVERSAL_POWER..1
(-125 3700);
FORCEPROP 3 LASTPIN (-125 3650) SIG_NAME P3V3_AUX\g
J 0
(-115 3660);
DISPLAY 0.659574 (-115 3660);
PAINT MONO (-115 3660);
DISPLAY INVISIBLE (-115 3660);
FORCEPROP 1 LAST HDL_POWER P3V3_AUX
J 1
(-125 3750);
DISPLAY 0.872340 (-125 3750);
PAINT GREEN (-125 3750);
FORCEPROP 1 LAST PATH I5
J 0
(-75 3725);
DISPLAY 0.872340 (-75 3725);
PAINT AQUA (-75 3725);
DISPLAY INVISIBLE (-75 3725);
FORCEPROP 2 LAST CDS_LIB logical_power
J 0
(-125 3700);
PAINT MONO (-125 3700);
DISPLAY INVISIBLE (-125 3700);
FORCEADD Q_RES..1
(-1125 2775);
FORCEPROP 1 LAST PART_NUMBER CS21002FB06
J 0
(-1225 2850);
DISPLAY 0.404255 (-1225 2850);
DISPLAY INVISIBLE (-1225 2850);
FORCEPROP 1 LAST TOLERANCE 1%
J 0
(-950 2775);
DISPLAY 0.510638 (-950 2775);
FORCEPROP 1 LAST MATERIAL EMPTY
J 0
(-875 2775);
DISPLAY 0.510638 (-875 2775);
PAINT RED (-875 2775);
FORCEPROP 1 LAST VALUE 1K
J 2
(-975 2775);
DISPLAY 0.510638 (-975 2775);
FORCEPROP 1 LAST PACK_TYPE 0402LF
J 0
(-1225 2875);
DISPLAY 0.404255 (-1225 2875);
FORCEPROP 1 LAST WATTAGE 1/16W
J 2
(-975 2875);
DISPLAY 0.404255 (-975 2875);
FORCEPROP 1 LAST $LOCATION R1197
J 0
(-1350 2775);
DISPLAY 0.638298 (-1350 2775);
FORCEPROP 1 LASTPIN (-1225 2775) $PN 1
J 0
(-1213 2787);
DISPLAY 0.787234 (-1213 2787);
FORCEPROP 1 LASTPIN (-1025 2775) $PN 2
J 0
(-1063 2787);
DISPLAY 0.787234 (-1063 2787);
FORCEPROP 2 LAST CDS_LIB pure_quanta
J 0
(-1125 2775);
PAINT MONO (-1125 2775);
DISPLAY INVISIBLE (-1125 2775);
FORCEPROP 1 LAST PATH I50
J 0
(-1175 2925);
DISPLAY 0.978723 (-1175 2925);
PAINT WHITE (-1175 2925);
DISPLAY INVISIBLE (-1175 2925);
FORCEPROP 2 LAST CDS_LOCATION R1197
J 0
(-1175 2975);
DISPLAY 1.021277 (-1175 2975);
DISPLAY INVISIBLE (-1175 2975);
FORCEPROP 2 LAST $SEC 1
J 0
(-1175 2975);
DISPLAY 0.680851 (-1175 2975);
PAINT MONO (-1175 2975);
DISPLAY INVISIBLE (-1175 2975);
FORCEPROP 2 LAST CDS_SEC 1
J 0
(-1175 2975);
DISPLAY 1.021277 (-1175 2975);
DISPLAY INVISIBLE (-1175 2975);
FORCEADD UNIVERSAL_GND..1
(-1425 2675);
FORCEPROP 3 LASTPIN (-1425 2725) SIG_NAME GND\g
J 0
(-1415 2735);
DISPLAY 0.659574 (-1415 2735);
PAINT MONO (-1415 2735);
DISPLAY INVISIBLE (-1415 2735);
FORCEPROP 2 LAST CDS_LIB logical_power
J 0
(-1425 2675);
PAINT MONO (-1425 2675);
DISPLAY INVISIBLE (-1425 2675);
FORCEPROP 1 LAST PATH I51
J 0
(-1350 2675);
DISPLAY 0.872340 (-1350 2675);
PAINT AQUA (-1350 2675);
DISPLAY INVISIBLE (-1350 2675);
FORCEPROP 1 LAST HDL_POWER GND
J 1
(-1400 2600);
DISPLAY 0.872340 (-1400 2600);
PAINT GREEN (-1400 2600);
DISPLAY INVISIBLE (-1400 2600);
FORCEADD OFFPAGE..1
R 2
(4200 2675);
FORCEPROP 2 LAST $XR0 182 
J 0
(4386 2675);
DISPLAY 0.638298 (4386 2675);
PAINT MONO (4386 2675);
FORCEPROP 2 LAST CDS_LIB standard
J 0
(4200 2675);
PAINT MONO (4200 2675);
DISPLAY INVISIBLE (4200 2675);
FORCEPROP 2 LAST PATH I53
J 0
(4375 2750);
DISPLAY 1.021277 (4375 2750);
DISPLAY INVISIBLE (4375 2750);
FORCEPROP 1 LAST COMMENT_BODY TRUE
J 2
(4075 2575);
DISPLAY 0.872340 (4075 2575);
PAINT GREEN (4075 2575);
DISPLAY INVISIBLE (4075 2575);
FORCEPROP 1 LAST OFFPAGE TRUE
J 2
(3875 2550);
DISPLAY 0.872340 (3875 2550);
DISPLAY INVISIBLE (3875 2550);
FORCEADD OFFPAGE..1
R 2
(4200 2625);
FORCEPROP 2 LAST $XR0 182 
J 0
(4386 2625);
DISPLAY 0.638298 (4386 2625);
PAINT MONO (4386 2625);
FORCEPROP 1 LAST COMMENT_BODY TRUE
J 2
(4075 2525);
DISPLAY 0.872340 (4075 2525);
PAINT GREEN (4075 2525);
DISPLAY INVISIBLE (4075 2525);
FORCEPROP 1 LAST OFFPAGE TRUE
J 2
(3875 2500);
DISPLAY 0.872340 (3875 2500);
DISPLAY INVISIBLE (3875 2500);
FORCEPROP 2 LAST PATH I54
J 0
(4375 2700);
DISPLAY 1.021277 (4375 2700);
DISPLAY INVISIBLE (4375 2700);
FORCEPROP 2 LAST CDS_LIB standard
J 0
(4200 2625);
PAINT MONO (4200 2625);
DISPLAY INVISIBLE (4200 2625);
FORCEADD OFFPAGE..1
(2450 350);
FORCEPROP 2 LAST $XR0 16 
J 0
(2199 350);
DISPLAY 0.638298 (2199 350);
PAINT MONO (2199 350);
FORCEPROP 2 LAST PATH I55
J 0
(2175 400);
DISPLAY 1.021277 (2175 400);
DISPLAY INVISIBLE (2175 400);
FORCEPROP 1 LAST COMMENT_BODY TRUE
J 0
(2575 250);
DISPLAY 1.170213 (2575 250);
PAINT GREEN (2575 250);
DISPLAY INVISIBLE (2575 250);
FORCEPROP 1 LAST OFFPAGE TRUE
J 0
(2775 225);
DISPLAY 0.872340 (2775 225);
DISPLAY INVISIBLE (2775 225);
FORCEPROP 2 LAST CDS_LIB standard
J 0
(2450 350);
PAINT MONO (2450 350);
DISPLAY INVISIBLE (2450 350);
FORCEADD OFFPAGE..2
(5600 350);
FORCEPROP 2 LAST $XR0 182 
J 0
(5789 350);
DISPLAY 0.638298 (5789 350);
PAINT MONO (5789 350);
FORCEPROP 1 LAST OFFPAGE TRUE
J 0
(5925 225);
DISPLAY 0.872340 (5925 225);
PAINT GREEN (5925 225);
DISPLAY INVISIBLE (5925 225);
FORCEPROP 1 LAST COMMENT_BODY TRUE
J 0
(5555 255);
DISPLAY 0.872340 (5555 255);
PAINT GREEN (5555 255);
DISPLAY INVISIBLE (5555 255);
FORCEPROP 2 LAST PATH I56
J 0
(5800 400);
DISPLAY 1.021277 (5800 400);
DISPLAY INVISIBLE (5800 400);
FORCEPROP 2 LAST CDS_LIB standard
J 0
(5600 350);
PAINT MONO (5600 350);
DISPLAY INVISIBLE (5600 350);
FORCEADD OFFPAGE..2
(5600 100);
FORCEPROP 2 LAST $XR0 182 
J 0
(5789 100);
DISPLAY 0.638298 (5789 100);
PAINT MONO (5789 100);
FORCEPROP 2 LAST CDS_LIB standard
J 0
(5600 100);
PAINT MONO (5600 100);
DISPLAY INVISIBLE (5600 100);
FORCEPROP 1 LAST OFFPAGE TRUE
J 0
(5925 -25);
DISPLAY 0.872340 (5925 -25);
PAINT GREEN (5925 -25);
DISPLAY INVISIBLE (5925 -25);
FORCEPROP 1 LAST COMMENT_BODY TRUE
J 0
(5555 5);
DISPLAY 0.872340 (5555 5);
PAINT GREEN (5555 5);
DISPLAY INVISIBLE (5555 5);
FORCEPROP 2 LAST PATH I57
J 0
(5800 150);
DISPLAY 1.021277 (5800 150);
DISPLAY INVISIBLE (5800 150);
FORCEADD Q_RES..1
(3850 100);
FORCEPROP 1 LAST PART_NUMBER CS04992FB07
J 0
(3750 175);
DISPLAY 0.638298 (3750 175);
DISPLAY INVISIBLE (3750 175);
FORCEPROP 1 LAST TOLERANCE 1%
J 0
(4125 100);
DISPLAY 0.638298 (4125 100);
FORCEPROP 1 LAST VALUE 49.9
J 2
(4250 100);
DISPLAY 0.638298 (4250 100);
FORCEPROP 1 LAST WATTAGE 1/16W
J 2
(4075 225);
DISPLAY 0.638298 (4075 225);
FORCEPROP 1 LAST PACK_TYPE 0402LF
J 0
(4200 100);
DISPLAY 0.638298 (4200 100);
FORCEPROP 1 LAST MATERIAL CHIP
J 0
(3750 225);
DISPLAY 0.638298 (3750 225);
FORCEPROP 1 LAST $LOCATION R1201
J 0
(3625 100);
DISPLAY 0.638298 (3625 100);
FORCEPROP 1 LASTPIN (3750 100) $PN 1
J 0
(3762 112);
DISPLAY 0.787234 (3762 112);
FORCEPROP 1 LASTPIN (3950 100) $PN 2
J 0
(3912 112);
DISPLAY 0.787234 (3912 112);
FORCEPROP 2 LAST CDS_LIB pure_quanta
J 0
(3850 100);
PAINT MONO (3850 100);
DISPLAY INVISIBLE (3850 100);
FORCEPROP 1 LAST PATH I58
J 0
(3800 250);
DISPLAY 0.978723 (3800 250);
PAINT WHITE (3800 250);
DISPLAY INVISIBLE (3800 250);
FORCEPROP 2 LAST CDS_LOCATION R1201
J 0
(3800 300);
DISPLAY 1.021277 (3800 300);
DISPLAY INVISIBLE (3800 300);
FORCEPROP 2 LAST $SEC 1
J 0
(3800 300);
DISPLAY 0.680851 (3800 300);
PAINT MONO (3800 300);
DISPLAY INVISIBLE (3800 300);
FORCEPROP 2 LAST CDS_SEC 1
J 0
(3800 300);
DISPLAY 1.021277 (3800 300);
DISPLAY INVISIBLE (3800 300);
FORCEADD OFFPAGE..1
(2450 100);
FORCEPROP 2 LAST $XR0 16 
J 0
(2199 100);
DISPLAY 0.638298 (2199 100);
PAINT MONO (2199 100);
FORCEPROP 2 LAST CDS_LIB standard
J 0
(2450 100);
PAINT MONO (2450 100);
DISPLAY INVISIBLE (2450 100);
FORCEPROP 1 LAST OFFPAGE TRUE
J 0
(2775 -25);
DISPLAY 0.872340 (2775 -25);
DISPLAY INVISIBLE (2775 -25);
FORCEPROP 1 LAST COMMENT_BODY TRUE
J 0
(2575 0);
DISPLAY 1.170213 (2575 0);
PAINT GREEN (2575 0);
DISPLAY INVISIBLE (2575 0);
FORCEPROP 2 LAST PATH I59
J 0
(2175 150);
DISPLAY 1.021277 (2175 150);
DISPLAY INVISIBLE (2175 150);
FORCEADD Q_RES..1
(3850 350);
FORCEPROP 1 LAST PART_NUMBER CS11002FB07
J 0
(3750 425);
DISPLAY 0.638298 (3750 425);
DISPLAY INVISIBLE (3750 425);
FORCEPROP 1 LAST WATTAGE 1/16W
J 2
(4075 475);
DISPLAY 0.638298 (4075 475);
FORCEPROP 1 LAST PACK_TYPE 0402LF
J 0
(4200 350);
DISPLAY 0.638298 (4200 350);
FORCEPROP 1 LAST TOLERANCE 1%
J 0
(4100 350);
DISPLAY 0.638298 (4100 350);
FORCEPROP 1 LAST VALUE 100
J 2
(4075 350);
DISPLAY 0.638298 (4075 350);
FORCEPROP 1 LAST MATERIAL CHIP
J 0
(3750 475);
DISPLAY 0.638298 (3750 475);
FORCEPROP 1 LAST $LOCATION R1200
J 0
(3625 350);
DISPLAY 0.638298 (3625 350);
FORCEPROP 1 LASTPIN (3750 350) $PN 1
J 0
(3762 362);
DISPLAY 0.787234 (3762 362);
FORCEPROP 1 LASTPIN (3950 350) $PN 2
J 0
(3912 362);
DISPLAY 0.787234 (3912 362);
FORCEPROP 1 LAST PATH I60
J 0
(3800 500);
DISPLAY 0.978723 (3800 500);
PAINT WHITE (3800 500);
DISPLAY INVISIBLE (3800 500);
FORCEPROP 2 LAST CDS_LIB pure_quanta
J 0
(3850 350);
PAINT MONO (3850 350);
DISPLAY INVISIBLE (3850 350);
FORCEPROP 2 LAST CDS_LOCATION R1200
J 0
(3800 550);
DISPLAY 1.021277 (3800 550);
DISPLAY INVISIBLE (3800 550);
FORCEPROP 2 LAST $SEC 1
J 0
(3800 550);
DISPLAY 0.680851 (3800 550);
PAINT MONO (3800 550);
DISPLAY INVISIBLE (3800 550);
FORCEPROP 2 LAST CDS_SEC 1
J 0
(3800 550);
DISPLAY 1.021277 (3800 550);
DISPLAY INVISIBLE (3800 550);
FORCEADD OFFPAGE..1
R 2
(4200 2525);
FORCEPROP 2 LAST $XR0 203 
J 0
(4386 2525);
DISPLAY 0.638298 (4386 2525);
PAINT MONO (4386 2525);
FORCEPROP 2 LAST CDS_LIB standard
J 0
(4200 2525);
PAINT MONO (4200 2525);
DISPLAY INVISIBLE (4200 2525);
FORCEPROP 2 LAST PATH I61
J 0
(4400 2575);
DISPLAY 1.021277 (4400 2575);
DISPLAY INVISIBLE (4400 2575);
FORCEPROP 1 LAST OFFPAGE TRUE
J 2
(3875 2400);
DISPLAY 0.872340 (3875 2400);
DISPLAY INVISIBLE (3875 2400);
FORCEPROP 1 LAST COMMENT_BODY TRUE
J 2
(4075 2425);
DISPLAY 0.872340 (4075 2425);
PAINT GREEN (4075 2425);
DISPLAY INVISIBLE (4075 2425);
FORCEADD OFFPAGE..1
R 2
(4200 3125);
FORCEPROP 2 LAST $XR0 182 
J 0
(4386 3125);
DISPLAY 0.638298 (4386 3125);
PAINT MONO (4386 3125);
FORCEPROP 2 LAST CDS_LIB standard
J 0
(4200 3125);
PAINT MONO (4200 3125);
DISPLAY INVISIBLE (4200 3125);
FORCEPROP 2 LAST PATH I62
J 0
(4400 3175);
DISPLAY 1.021277 (4400 3175);
DISPLAY INVISIBLE (4400 3175);
FORCEPROP 1 LAST OFFPAGE TRUE
J 2
(3875 3000);
DISPLAY 0.872340 (3875 3000);
DISPLAY INVISIBLE (3875 3000);
FORCEPROP 1 LAST COMMENT_BODY TRUE
J 2
(4075 3025);
DISPLAY 0.872340 (4075 3025);
PAINT GREEN (4075 3025);
DISPLAY INVISIBLE (4075 3025);
FORCEADD Q_RES..2
R 2
(-250 3375);
FORCEPROP 1 LAST PART_NUMBER CS24752FB03
J 2
(-290 3250);
DISPLAY 0.638298 (-290 3250);
DISPLAY INVISIBLE (-290 3250);
FORCEPROP 1 LAST TOLERANCE 1%
J 2
(-295 3400);
DISPLAY 0.638298 (-295 3400);
FORCEPROP 1 LAST WATTAGE 1/16W
J 2
(-290 3350);
DISPLAY 0.638298 (-290 3350);
FORCEPROP 1 LAST MATERIAL CHIP
J 2
(-290 3300);
DISPLAY 0.638298 (-290 3300);
FORCEPROP 1 LAST VALUE 4.75K
J 2
(-295 3450);
DISPLAY 0.638298 (-295 3450);
FORCEPROP 1 LAST PACK_TYPE 0402LF
J 2
(-290 3200);
DISPLAY 0.638298 (-290 3200);
FORCEPROP 1 LAST $LOCATION R696
J 2
(-295 3500);
DISPLAY 0.978723 (-295 3500);
FORCEPROP 1 LASTPIN (-250 3475) $PN 1
J 2
(-255 3437);
DISPLAY 0.787234 (-255 3437);
FORCEPROP 1 LASTPIN (-250 3275) $PN 2
J 2
(-255 3285);
DISPLAY 0.787234 (-255 3285);
FORCEPROP 2 LAST CDS_LIB pure_quanta
J 2
(-250 3375);
PAINT MONO (-250 3375);
DISPLAY INVISIBLE (-250 3375);
FORCEPROP 1 LAST PATH I63
J 2
(-300 3550);
DISPLAY 0.978723 (-300 3550);
PAINT WHITE (-300 3550);
DISPLAY INVISIBLE (-300 3550);
FORCEPROP 2 LAST CDS_LOCATION R696
J 0
(-300 3600);
DISPLAY 1.021277 (-300 3600);
DISPLAY INVISIBLE (-300 3600);
FORCEPROP 2 LAST $SEC 1
J 0
(-300 3600);
DISPLAY 0.680851 (-300 3600);
PAINT MONO (-300 3600);
DISPLAY INVISIBLE (-300 3600);
FORCEPROP 2 LAST CDS_SEC 1
J 0
(-300 3600);
DISPLAY 1.021277 (-300 3600);
DISPLAY INVISIBLE (-300 3600);
FORCEADD OFFPAGE..1
(-1550 375);
FORCEPROP 2 LAST $XR0 215 
J 0
(-1802 375);
DISPLAY 0.638298 (-1802 375);
PAINT MONO (-1802 375);
FORCEPROP 1 LAST OFFPAGE TRUE
J 0
(-1225 250);
DISPLAY 0.872340 (-1225 250);
DISPLAY INVISIBLE (-1225 250);
FORCEPROP 1 LAST COMMENT_BODY TRUE
J 0
(-1425 275);
DISPLAY 1.170213 (-1425 275);
PAINT GREEN (-1425 275);
DISPLAY INVISIBLE (-1425 275);
FORCEPROP 2 LAST CDS_LIB standard
J 0
(-1550 375);
PAINT MONO (-1550 375);
DISPLAY INVISIBLE (-1550 375);
FORCEPROP 2 LAST PATH I64
J 0
(-1825 425);
DISPLAY 1.021277 (-1825 425);
DISPLAY INVISIBLE (-1825 425);
FORCEADD OFFPAGE..2
(1250 375);
FORCEPROP 2 LAST $XR0 182 
J 0
(1439 375);
DISPLAY 0.638298 (1439 375);
PAINT MONO (1439 375);
FORCEPROP 1 LAST OFFPAGE TRUE
J 0
(1575 250);
DISPLAY 0.872340 (1575 250);
PAINT GREEN (1575 250);
DISPLAY INVISIBLE (1575 250);
FORCEPROP 1 LAST COMMENT_BODY TRUE
J 0
(1205 280);
DISPLAY 0.872340 (1205 280);
PAINT GREEN (1205 280);
DISPLAY INVISIBLE (1205 280);
FORCEPROP 2 LAST CDS_LIB standard
J 0
(1250 375);
PAINT MONO (1250 375);
DISPLAY INVISIBLE (1250 375);
FORCEPROP 2 LAST PATH I65
J 0
(1450 425);
DISPLAY 1.021277 (1450 425);
DISPLAY INVISIBLE (1450 425);
FORCEADD Q_RES..1
(-150 375);
FORCEPROP 1 LAST PART_NUMBER CS03322FB03
J 0
(-275 425);
DISPLAY 0.638298 (-275 425);
DISPLAY INVISIBLE (-275 425);
FORCEPROP 1 LAST WATTAGE 1/16W
J 2
(50 475);
DISPLAY 0.638298 (50 475);
FORCEPROP 1 LAST PACK_TYPE 0402LF
J 0
(150 375);
DISPLAY 0.638298 (150 375);
FORCEPROP 1 LAST MATERIAL CHIP
J 0
(-275 475);
DISPLAY 0.638298 (-275 475);
FORCEPROP 1 LAST VALUE 33.2
J 2
(25 375);
DISPLAY 0.638298 (25 375);
FORCEPROP 1 LAST TOLERANCE 1%
J 0
(50 375);
DISPLAY 0.638298 (50 375);
FORCEPROP 1 LAST $LOCATION R697
J 0
(-375 375);
DISPLAY 0.638298 (-375 375);
FORCEPROP 1 LASTPIN (-250 375) $PN 1
J 0
(-238 387);
DISPLAY 0.787234 (-238 387);
FORCEPROP 1 LASTPIN (-50 375) $PN 2
J 0
(-88 387);
DISPLAY 0.787234 (-88 387);
FORCEPROP 2 LAST CDS_LIB pure_quanta
J 0
(-150 375);
PAINT MONO (-150 375);
DISPLAY INVISIBLE (-150 375);
FORCEPROP 1 LAST PATH I66
J 0
(-200 525);
DISPLAY 0.978723 (-200 525);
PAINT WHITE (-200 525);
DISPLAY INVISIBLE (-200 525);
FORCEPROP 2 LAST CDS_LOCATION R697
J 0
(-200 575);
DISPLAY 1.021277 (-200 575);
DISPLAY INVISIBLE (-200 575);
FORCEPROP 2 LAST $SEC 1
J 0
(-200 575);
DISPLAY 0.680851 (-200 575);
PAINT MONO (-200 575);
DISPLAY INVISIBLE (-200 575);
FORCEPROP 2 LAST CDS_SEC 1
J 0
(-200 575);
DISPLAY 1.021277 (-200 575);
DISPLAY INVISIBLE (-200 575);
FORCEADD OFFPAGE..1
(-425 2725);
FORCEPROP 2 LAST $XR0 199 
J 0
(-677 2725);
DISPLAY 0.638298 (-677 2725);
PAINT MONO (-677 2725);
FORCEPROP 2 LAST CDS_LIB standard
J 0
(-425 2725);
PAINT MONO (-425 2725);
DISPLAY INVISIBLE (-425 2725);
FORCEPROP 2 LAST PATH I73
J 0
(-375 2800);
DISPLAY 1.021277 (-375 2800);
DISPLAY INVISIBLE (-375 2800);
FORCEPROP 1 LAST COMMENT_BODY TRUE
J 0
(-300 2625);
DISPLAY 1.170213 (-300 2625);
PAINT GREEN (-300 2625);
DISPLAY INVISIBLE (-300 2625);
FORCEPROP 1 LAST OFFPAGE TRUE
J 0
(-100 2600);
DISPLAY 0.872340 (-100 2600);
DISPLAY INVISIBLE (-100 2600);
FORCEADD Q_RES..2
(5400 600);
FORCEPROP 1 LAST PART_NUMBER CS12002FB06
J 0
(5440 425);
DISPLAY 0.638298 (5440 425);
DISPLAY INVISIBLE (5440 425);
FORCEPROP 1 LAST PACK_TYPE 0402LF
J 0
(5440 475);
DISPLAY 0.638298 (5440 475);
FORCEPROP 1 LAST WATTAGE 1/16W
J 0
(5440 575);
DISPLAY 0.638298 (5440 575);
FORCEPROP 1 LAST MATERIAL EMPTY
J 0
(5440 525);
DISPLAY 0.638298 (5440 525);
PAINT RED (5440 525);
FORCEPROP 1 LAST TOLERANCE 1%
J 0
(5445 625);
DISPLAY 0.638298 (5445 625);
FORCEPROP 1 LAST VALUE 200
J 0
(5445 675);
DISPLAY 0.638298 (5445 675);
FORCEPROP 1 LAST $LOCATION R1486
J 0
(5445 725);
DISPLAY 0.638298 (5445 725);
FORCEPROP 1 LASTPIN (5400 700) $PN 1
J 0
(5405 662);
DISPLAY 0.787234 (5405 662);
FORCEPROP 1 LASTPIN (5400 500) $PN 2
J 0
(5405 510);
DISPLAY 0.787234 (5405 510);
FORCEPROP 2 LAST CDS_LIB pure_quanta
J 0
(5400 600);
PAINT MONO (5400 600);
DISPLAY INVISIBLE (5400 600);
FORCEPROP 1 LAST PATH I74
J 0
(5450 775);
DISPLAY 0.978723 (5450 775);
PAINT WHITE (5450 775);
DISPLAY INVISIBLE (5450 775);
FORCEPROP 2 LAST CDS_LOCATION R1486
J 0
(5450 825);
DISPLAY 1.021277 (5450 825);
DISPLAY INVISIBLE (5450 825);
FORCEPROP 2 LAST $SEC 1
J 0
(5450 825);
DISPLAY 0.680851 (5450 825);
PAINT MONO (5450 825);
DISPLAY INVISIBLE (5450 825);
FORCEPROP 2 LAST CDS_SEC 1
J 0
(5450 825);
DISPLAY 1.021277 (5450 825);
DISPLAY INVISIBLE (5450 825);
FORCEADD Q_RES..2
(5125 600);
FORCEPROP 1 LAST PART_NUMBER CS12002FB06
J 0
(5165 425);
DISPLAY 0.638298 (5165 425);
DISPLAY INVISIBLE (5165 425);
FORCEPROP 1 LAST TOLERANCE 1%
J 0
(5170 625);
DISPLAY 0.638298 (5170 625);
FORCEPROP 1 LAST WATTAGE 1/16W
J 0
(5165 575);
DISPLAY 0.638298 (5165 575);
FORCEPROP 1 LAST MATERIAL EMPTY
J 0
(5165 525);
DISPLAY 0.638298 (5165 525);
PAINT RED (5165 525);
FORCEPROP 1 LAST VALUE 200
J 0
(5170 675);
DISPLAY 0.638298 (5170 675);
FORCEPROP 1 LAST PACK_TYPE 0402LF
J 0
(5165 475);
DISPLAY 0.638298 (5165 475);
FORCEPROP 1 LAST $LOCATION R1485
J 0
(5170 725);
DISPLAY 0.638298 (5170 725);
FORCEPROP 1 LASTPIN (5125 700) $PN 1
J 0
(5130 662);
DISPLAY 0.787234 (5130 662);
FORCEPROP 1 LASTPIN (5125 500) $PN 2
J 0
(5130 510);
DISPLAY 0.787234 (5130 510);
FORCEPROP 2 LAST CDS_LIB pure_quanta
J 0
(5125 600);
PAINT MONO (5125 600);
DISPLAY INVISIBLE (5125 600);
FORCEPROP 1 LAST PATH I75
J 0
(5175 775);
DISPLAY 0.978723 (5175 775);
PAINT WHITE (5175 775);
DISPLAY INVISIBLE (5175 775);
FORCEPROP 2 LAST CDS_LOCATION R1485
J 0
(5175 825);
DISPLAY 1.021277 (5175 825);
DISPLAY INVISIBLE (5175 825);
FORCEPROP 2 LAST $SEC 1
J 0
(5175 825);
DISPLAY 0.680851 (5175 825);
PAINT MONO (5175 825);
DISPLAY INVISIBLE (5175 825);
FORCEPROP 2 LAST CDS_SEC 1
J 0
(5175 825);
DISPLAY 1.021277 (5175 825);
DISPLAY INVISIBLE (5175 825);
FORCEADD UNIVERSAL_POWER..1
(5125 850);
FORCEPROP 3 LASTPIN (5125 800) SIG_NAME PVNN_TERM_CPU0\g
J 0
(5135 810);
DISPLAY 0.659574 (5135 810);
PAINT MONO (5135 810);
DISPLAY INVISIBLE (5135 810);
FORCEPROP 1 LAST HDL_POWER PVNN_TERM_CPU0
J 1
(5125 900);
DISPLAY 0.872340 (5125 900);
PAINT GREEN (5125 900);
FORCEPROP 1 LAST PATH I76
J 0
(5175 875);
DISPLAY 0.872340 (5175 875);
PAINT AQUA (5175 875);
DISPLAY INVISIBLE (5175 875);
FORCEPROP 2 LAST CDS_LIB logical_power
J 0
(5125 850);
PAINT MONO (5125 850);
DISPLAY INVISIBLE (5125 850);
FORCEADD Q_RES..1
(-1375 2475);
FORCEPROP 1 LAST PART_NUMBER CS31002FB08
J 0
(-1500 2525);
DISPLAY 0.319149 (-1500 2525);
DISPLAY INVISIBLE (-1500 2525);
FORCEPROP 1 LAST PACK_TYPE 0402LF
J 0
(-1500 2550);
DISPLAY 0.319149 (-1500 2550);
FORCEPROP 1 LAST WATTAGE 1/16W
J 2
(-1300 2550);
DISPLAY 0.319149 (-1300 2550);
FORCEPROP 1 LAST VALUE 10K
J 2
(-1200 2475);
DISPLAY 0.510638 (-1200 2475);
FORCEPROP 1 LAST MATERIAL CHIP
J 0
(-1100 2475);
DISPLAY 0.510638 (-1100 2475);
FORCEPROP 1 LAST TOLERANCE 1%
J 0
(-1175 2475);
DISPLAY 0.510638 (-1175 2475);
FORCEPROP 1 LAST $LOCATION R453
J 0
(-1600 2475);
DISPLAY 0.638298 (-1600 2475);
FORCEPROP 1 LASTPIN (-1475 2475) $PN 1
J 0
(-1463 2487);
DISPLAY 0.787234 (-1463 2487);
FORCEPROP 1 LASTPIN (-1275 2475) $PN 2
J 0
(-1313 2487);
DISPLAY 0.787234 (-1313 2487);
FORCEPROP 1 LAST PATH I77
J 0
(-1425 2625);
DISPLAY 0.978723 (-1425 2625);
PAINT WHITE (-1425 2625);
DISPLAY INVISIBLE (-1425 2625);
FORCEPROP 2 LAST CDS_LIB pure_quanta
J 0
(-1375 2475);
PAINT MONO (-1375 2475);
DISPLAY INVISIBLE (-1375 2475);
FORCEPROP 2 LAST CDS_LOCATION R453
J 0
(-1425 2675);
DISPLAY 1.021277 (-1425 2675);
DISPLAY INVISIBLE (-1425 2675);
FORCEPROP 2 LAST $SEC 1
J 0
(-1425 2675);
DISPLAY 0.680851 (-1425 2675);
PAINT MONO (-1425 2675);
DISPLAY INVISIBLE (-1425 2675);
FORCEPROP 2 LAST CDS_SEC 1
J 0
(-1425 2675);
DISPLAY 1.021277 (-1425 2675);
DISPLAY INVISIBLE (-1425 2675);
FORCEADD UNIVERSAL_POWER..1
(-1675 2600);
FORCEPROP 3 LASTPIN (-1675 2550) SIG_NAME P3V3_AUX\g
J 0
(-1665 2560);
DISPLAY 0.659574 (-1665 2560);
PAINT MONO (-1665 2560);
DISPLAY INVISIBLE (-1665 2560);
FORCEPROP 1 LAST HDL_POWER P3V3_AUX
J 1
(-1675 2650);
DISPLAY 0.872340 (-1675 2650);
PAINT GREEN (-1675 2650);
FORCEPROP 2 LAST CDS_LIB logical_power
J 0
(-1675 2600);
PAINT MONO (-1675 2600);
DISPLAY INVISIBLE (-1675 2600);
FORCEPROP 1 LAST PATH I78
J 0
(-1625 2625);
DISPLAY 0.872340 (-1625 2625);
PAINT AQUA (-1625 2625);
DISPLAY INVISIBLE (-1625 2625);
FORCEADD OFFPAGE..1
(-425 2975);
FORCEPROP 2 LAST $XR0 182 
J 0
(-677 2975);
DISPLAY 0.638298 (-677 2975);
PAINT MONO (-677 2975);
FORCEPROP 2 LAST PATH I8
J 0
(-375 3050);
DISPLAY 1.021277 (-375 3050);
DISPLAY INVISIBLE (-375 3050);
FORCEPROP 1 LAST COMMENT_BODY TRUE
J 0
(-300 2875);
DISPLAY 1.170213 (-300 2875);
PAINT GREEN (-300 2875);
DISPLAY INVISIBLE (-300 2875);
FORCEPROP 1 LAST OFFPAGE TRUE
J 0
(-100 2850);
DISPLAY 0.872340 (-100 2850);
DISPLAY INVISIBLE (-100 2850);
FORCEPROP 2 LAST CDS_LIB standard
J 0
(-425 2975);
PAINT MONO (-425 2975);
DISPLAY INVISIBLE (-425 2975);
FORCEADD UNIVERSAL_POWER..1
(4450 -150);
FORCEPROP 3 LASTPIN (4450 -200) SIG_NAME P3V3_AUX\g
J 0
(4460 -190);
DISPLAY 0.659574 (4460 -190);
PAINT MONO (4460 -190);
DISPLAY INVISIBLE (4460 -190);
FORCEPROP 1 LAST HDL_POWER P3V3_AUX
J 1
(4450 -100);
DISPLAY 0.872340 (4450 -100);
PAINT GREEN (4450 -100);
FORCEPROP 1 LAST PATH I80
J 0
(4500 -125);
DISPLAY 0.872340 (4500 -125);
PAINT AQUA (4500 -125);
DISPLAY INVISIBLE (4500 -125);
FORCEPROP 2 LAST CDS_LIB logical_power
J 0
(4450 -150);
PAINT MONO (4450 -150);
DISPLAY INVISIBLE (4450 -150);
FORCEADD OFFPAGE..5
(2450 -350);
FORCEPROP 2 LAST $XR0 182 
J 0
(2195 -350);
DISPLAY 0.638298 (2195 -350);
PAINT MONO (2195 -350);
FORCEPROP 2 LAST CDS_LIB standard
J 0
(2450 -350);
PAINT MONO (2450 -350);
DISPLAY INVISIBLE (2450 -350);
FORCEPROP 1 LAST OFFPAGE TRUE
J 0
(2775 -475);
DISPLAY 0.872340 (2775 -475);
DISPLAY INVISIBLE (2775 -475);
FORCEPROP 1 LAST COMMENT_BODY TRUE
J 0
(2550 -425);
DISPLAY 1.170213 (2550 -425);
PAINT GREEN (2550 -425);
DISPLAY INVISIBLE (2550 -425);
FORCEPROP 2 LAST PATH I81
J 0
(2175 -300);
DISPLAY 1.021277 (2175 -300);
DISPLAY INVISIBLE (2175 -300);
FORCEADD Q_RES..1
(3850 -350);
FORCEPROP 1 LAST PART_NUMBER CS22492FB05
J 0
(3700 -275);
DISPLAY 0.510638 (3700 -275);
DISPLAY INVISIBLE (3700 -275);
FORCEPROP 1 LAST PACK_TYPE 0402LF
J 0
(3700 -225);
DISPLAY 0.510638 (3700 -225);
FORCEPROP 1 LAST WATTAGE 1/16W
J 2
(4050 -225);
DISPLAY 0.510638 (4050 -225);
FORCEPROP 1 LAST MATERIAL CHIP
J 0
(4200 -350);
DISPLAY 0.510638 (4200 -350);
FORCEPROP 1 LAST VALUE 2.49K
J 2
(4075 -350);
DISPLAY 0.510638 (4075 -350);
FORCEPROP 1 LAST TOLERANCE 1%
J 0
(4100 -350);
DISPLAY 0.510638 (4100 -350);
FORCEPROP 1 LAST $LOCATION R1675
J 0
(3625 -350);
DISPLAY 0.638298 (3625 -350);
FORCEPROP 1 LASTPIN (3750 -350) $PN 1
J 0
(3762 -338);
DISPLAY 0.787234 (3762 -338);
FORCEPROP 1 LASTPIN (3950 -350) $PN 2
J 0
(3912 -338);
DISPLAY 0.787234 (3912 -338);
FORCEPROP 2 LAST CDS_LIB pure_quanta
J 0
(3850 -350);
PAINT MONO (3850 -350);
DISPLAY INVISIBLE (3850 -350);
FORCEPROP 1 LAST PATH I82
J 0
(3800 -200);
DISPLAY 0.978723 (3800 -200);
PAINT WHITE (3800 -200);
DISPLAY INVISIBLE (3800 -200);
FORCEPROP 2 LAST CDS_LOCATION R1675
J 0
(3800 -150);
DISPLAY 1.021277 (3800 -150);
DISPLAY INVISIBLE (3800 -150);
FORCEPROP 2 LAST $SEC 1
J 0
(3800 -150);
DISPLAY 0.680851 (3800 -150);
PAINT MONO (3800 -150);
DISPLAY INVISIBLE (3800 -150);
FORCEPROP 2 LAST CDS_SEC 1
J 0
(3800 -150);
DISPLAY 1.021277 (3800 -150);
DISPLAY INVISIBLE (3800 -150);
FORCEADD OFFPAGE..1
(-425 2925);
FORCEPROP 2 LAST $XR2 240 
J 0
(-917 2925);
DISPLAY 0.638298 (-917 2925);
PAINT MONO (-917 2925);
FORCEPROP 2 LAST $XR1 219 
J 0
(-797 2925);
DISPLAY 0.638298 (-797 2925);
PAINT MONO (-797 2925);
FORCEPROP 2 LAST $XR0 222 
J 0
(-677 2925);
DISPLAY 0.638298 (-677 2925);
PAINT MONO (-677 2925);
FORCEPROP 1 LAST COMMENT_BODY TRUE
J 0
(-300 2825);
DISPLAY 1.170213 (-300 2825);
PAINT GREEN (-300 2825);
DISPLAY INVISIBLE (-300 2825);
FORCEPROP 1 LAST OFFPAGE TRUE
J 0
(-100 2800);
DISPLAY 0.872340 (-100 2800);
DISPLAY INVISIBLE (-100 2800);
FORCEPROP 2 LAST PATH I9
J 0
(-375 3000);
DISPLAY 1.021277 (-375 3000);
DISPLAY INVISIBLE (-375 3000);
FORCEPROP 2 LAST CDS_LIB standard
J 0
(-425 2925);
PAINT MONO (-425 2925);
DISPLAY INVISIBLE (-425 2925);
FORCEADD OFFPAGE..1
(-1550 -200);
FORCEPROP 2 LAST $XR0 182 
J 0
(-1802 -200);
DISPLAY 0.638298 (-1802 -200);
PAINT MONO (-1802 -200);
FORCEPROP 2 LAST PATH I90
J 0
(-1825 -150);
DISPLAY 1.021277 (-1825 -150);
DISPLAY INVISIBLE (-1825 -150);
FORCEPROP 1 LAST OFFPAGE TRUE
J 0
(-1225 -325);
DISPLAY 0.872340 (-1225 -325);
DISPLAY INVISIBLE (-1225 -325);
FORCEPROP 1 LAST COMMENT_BODY TRUE
J 0
(-1425 -300);
DISPLAY 1.170213 (-1425 -300);
PAINT GREEN (-1425 -300);
DISPLAY INVISIBLE (-1425 -300);
FORCEPROP 2 LAST CDS_LIB standard
J 0
(-1550 -200);
PAINT MONO (-1550 -200);
DISPLAY INVISIBLE (-1550 -200);
FORCEADD OFFPAGE..2
(1250 -200);
FORCEPROP 2 LAST $XR1 220 
J 0
(1559 -200);
DISPLAY 0.638298 (1559 -200);
PAINT MONO (1559 -200);
FORCEPROP 2 LAST $XR0 213 
J 0
(1439 -200);
DISPLAY 0.638298 (1439 -200);
PAINT MONO (1439 -200);
FORCEPROP 2 LAST PATH I91
J 0
(1450 -150);
DISPLAY 1.021277 (1450 -150);
DISPLAY INVISIBLE (1450 -150);
FORCEPROP 1 LAST OFFPAGE TRUE
J 0
(1575 -325);
DISPLAY 0.872340 (1575 -325);
PAINT GREEN (1575 -325);
DISPLAY INVISIBLE (1575 -325);
FORCEPROP 1 LAST COMMENT_BODY TRUE
J 0
(1205 -295);
DISPLAY 0.872340 (1205 -295);
PAINT GREEN (1205 -295);
DISPLAY INVISIBLE (1205 -295);
FORCEPROP 2 LAST CDS_LIB standard
J 0
(1250 -200);
PAINT MONO (1250 -200);
DISPLAY INVISIBLE (1250 -200);
FORCEADD OFFPAGE..5
(-425 3125);
FORCEPROP 2 LAST $XR0 182 
J 0
(-710 3125);
DISPLAY 0.638298 (-710 3125);
PAINT MONO (-710 3125);
FORCEPROP 1 LAST COMMENT_BODY TRUE
J 0
(-325 3050);
DISPLAY 1.170213 (-325 3050);
PAINT GREEN (-325 3050);
DISPLAY INVISIBLE (-325 3050);
FORCEPROP 1 LAST OFFPAGE TRUE
J 0
(-100 3000);
DISPLAY 0.872340 (-100 3000);
DISPLAY INVISIBLE (-100 3000);
FORCEPROP 2 LAST PATH I92
J 0
(-725 3175);
DISPLAY 1.021277 (-725 3175);
DISPLAY INVISIBLE (-725 3175);
FORCEPROP 2 LAST CDS_LIB standard
J 0
(-425 3125);
PAINT MONO (-425 3125);
DISPLAY INVISIBLE (-425 3125);
FORCEADD OFFPAGE..1
(-425 2375);
FORCEPROP 2 LAST $XR0 200 
J 0
(-677 2375);
DISPLAY 0.638298 (-677 2375);
PAINT MONO (-677 2375);
FORCEPROP 2 LAST CDS_LIB standard
J 0
(-425 2375);
DISPLAY INVISIBLE (-425 2375);
FORCEPROP 2 LAST PATH I93
J 0
(-700 2425);
DISPLAY 1.021277 (-700 2425);
DISPLAY INVISIBLE (-700 2425);
FORCEPROP 1 LAST OFFPAGE TRUE
J 0
(-100 2250);
DISPLAY 0.872340 (-100 2250);
DISPLAY INVISIBLE (-100 2250);
FORCEPROP 1 LAST COMMENT_BODY TRUE
J 0
(-300 2275);
DISPLAY 1.170213 (-300 2275);
PAINT GREEN (-300 2275);
DISPLAY INVISIBLE (-300 2275);
FORCEADD Q_RES..1
(3850 -600);
FORCEPROP 1 LAST PART_NUMBER CS21002FB06
J 0
(3675 -550);
DISPLAY 0.510638 (3675 -550);
DISPLAY INVISIBLE (3675 -550);
FORCEPROP 1 LAST WATTAGE 1/16W
J 2
(4000 -500);
DISPLAY 0.510638 (4000 -500);
FORCEPROP 1 LAST TOLERANCE 1%
J 0
(4100 -600);
DISPLAY 0.510638 (4100 -600);
FORCEPROP 1 LAST MATERIAL EMPTY
J 0
(4200 -600);
DISPLAY 0.510638 (4200 -600);
PAINT RED (4200 -600);
FORCEPROP 1 LAST PACK_TYPE 0402LF
J 0
(3675 -500);
DISPLAY 0.510638 (3675 -500);
FORCEPROP 1 LAST VALUE 1K
J 2
(4075 -600);
DISPLAY 0.510638 (4075 -600);
FORCEPROP 1 LAST LOCATION R1676
J 0
(3625 -600);
DISPLAY 0.638298 (3625 -600);
FORCEPROP 1 LASTPIN (3750 -600) $PN 1
J 0
(3762 -588);
DISPLAY 0.787234 (3762 -588);
PAINT MONO (3762 -588);
FORCEPROP 1 LASTPIN (3950 -600) $PN 2
J 0
(3912 -588);
DISPLAY 0.787234 (3912 -588);
PAINT MONO (3912 -588);
FORCEPROP 2 LAST CDS_LIB pure_quanta
J 0
(3850 -600);
DISPLAY INVISIBLE (3850 -600);
FORCEPROP 1 LAST PATH I94
J 0
(3800 -450);
DISPLAY 0.978723 (3800 -450);
PAINT WHITE (3800 -450);
DISPLAY INVISIBLE (3800 -450);
FORCEPROP 0 LAST $SEC 1
J 0
(4000 -475);
DISPLAY 0.680851 (4000 -475);
PAINT MONO (4000 -475);
DISPLAY INVISIBLE (4000 -475);
FORCEPROP 0 LAST CDS_SEC 1
J 0
(4000 -475);
DISPLAY 1.021277 (4000 -475);
DISPLAY INVISIBLE (4000 -475);
FORCEADD UNIVERSAL_GND..1
(4450 -725);
FORCEPROP 3 LASTPIN (4450 -675) SIG_NAME GND\g
J 0
(4460 -665);
DISPLAY 0.659574 (4460 -665);
PAINT MONO (4460 -665);
DISPLAY INVISIBLE (4460 -665);
FORCEPROP 2 LAST CDS_LIB logical_power
J 0
(4450 -725);
DISPLAY INVISIBLE (4450 -725);
FORCEPROP 1 LAST PATH I95
J 0
(4525 -725);
DISPLAY 0.872340 (4525 -725);
PAINT AQUA (4525 -725);
DISPLAY INVISIBLE (4525 -725);
FORCEPROP 1 LAST HDL_POWER GND
J 1
(4475 -800);
DISPLAY 0.872340 (4475 -800);
PAINT GREEN (4475 -800);
DISPLAY INVISIBLE (4475 -800);
FORCEADD Q_RES..2
(5025 2450);
FORCEPROP 1 LAST PART_NUMBER CS51002FB05
J 0
(5065 2325);
DISPLAY 0.978723 (5065 2325);
DISPLAY INVISIBLE (5065 2325);
FORCEPROP 1 LAST TOLERANCE 1%
J 0
(5070 2475);
DISPLAY 0.978723 (5070 2475);
FORCEPROP 1 LAST VALUE 1M
J 0
(5070 2525);
DISPLAY 0.978723 (5070 2525);
FORCEPROP 1 LAST MATERIAL CHIP
J 0
(5065 2375);
DISPLAY 0.978723 (5065 2375);
FORCEPROP 1 LAST WATTAGE 1/16W
J 0
(5065 2425);
DISPLAY 0.978723 (5065 2425);
FORCEPROP 1 LAST PACK_TYPE 0402LF
J 0
(5065 2275);
DISPLAY 0.978723 (5065 2275);
FORCEPROP 1 LAST $LOCATION R2966
J 0
(5070 2575);
DISPLAY 0.978723 (5070 2575);
FORCEPROP 1 LASTPIN (5025 2550) $PN 1
J 0
(5030 2512);
DISPLAY 0.787234 (5030 2512);
PAINT MONO (5030 2512);
FORCEPROP 1 LASTPIN (5025 2350) $PN 2
J 0
(5030 2360);
DISPLAY 0.787234 (5030 2360);
PAINT MONO (5030 2360);
FORCEPROP 1 LAST PATH I96
J 0
(5075 2625);
DISPLAY 0.978723 (5075 2625);
PAINT WHITE (5075 2625);
DISPLAY INVISIBLE (5075 2625);
FORCEPROP 2 LAST CDS_LIB pure_quanta
J 0
(5025 2450);
DISPLAY INVISIBLE (5025 2450);
FORCEPROP 0 LAST CDS_LOCATION R2966
J 0
(5075 2625);
DISPLAY 1.021277 (5075 2625);
DISPLAY INVISIBLE (5075 2625);
FORCEPROP 0 LAST $SEC 1
J 0
(5075 2625);
DISPLAY 0.680851 (5075 2625);
PAINT MONO (5075 2625);
DISPLAY INVISIBLE (5075 2625);
FORCEPROP 0 LAST CDS_SEC 1
J 0
(5075 2625);
DISPLAY 1.021277 (5075 2625);
DISPLAY INVISIBLE (5075 2625);
FORCEADD UNIVERSAL_POWER..1
(5025 2750);
FORCEPROP 3 LASTPIN (5025 2700) SIG_NAME P3V3_RTC_AUX\g
J 0
(5035 2710);
DISPLAY 0.659574 (5035 2710);
PAINT MONO (5035 2710);
DISPLAY INVISIBLE (5035 2710);
FORCEPROP 1 LAST HDL_POWER P3V3_RTC_AUX
J 1
(5025 2800);
DISPLAY 0.872340 (5025 2800);
PAINT GREEN (5025 2800);
FORCEPROP 1 LAST PATH I97
J 0
(5075 2775);
DISPLAY 0.872340 (5075 2775);
PAINT AQUA (5075 2775);
DISPLAY INVISIBLE (5075 2775);
FORCEPROP 2 LAST CDS_LIB logical_power
J 0
(5025 2750);
DISPLAY INVISIBLE (5025 2750);
FORCEADD Q_RES..2
(-125 3375);
FORCEPROP 1 LAST PART_NUMBER CS21002FB06
J 0
(-85 3250);
DISPLAY 0.510638 (-85 3250);
DISPLAY INVISIBLE (-85 3250);
FORCEPROP 1 LAST MATERIAL CHIP
J 0
(-85 3300);
DISPLAY 0.638298 (-85 3300);
FORCEPROP 1 LAST PACK_TYPE 0402LF
J 0
(-85 3200);
DISPLAY 0.638298 (-85 3200);
FORCEPROP 1 LAST VALUE 1K
J 0
(-80 3450);
DISPLAY 0.638298 (-80 3450);
FORCEPROP 1 LAST TOLERANCE 1%
J 0
(-80 3400);
DISPLAY 0.638298 (-80 3400);
FORCEPROP 1 LAST WATTAGE 1/16W
J 0
(-85 3350);
DISPLAY 0.638298 (-85 3350);
FORCEPROP 1 LAST LOCATION R494
J 0
(-80 3500);
DISPLAY 0.978723 (-80 3500);
FORCEPROP 1 LASTPIN (-125 3475) $PN 1
J 0
(-120 3437);
DISPLAY 0.787234 (-120 3437);
PAINT MONO (-120 3437);
FORCEPROP 1 LASTPIN (-125 3275) $PN 2
J 0
(-120 3285);
DISPLAY 0.787234 (-120 3285);
PAINT MONO (-120 3285);
FORCEPROP 1 LAST PATH I98
J 0
(-75 3550);
DISPLAY 0.978723 (-75 3550);
PAINT WHITE (-75 3550);
DISPLAY INVISIBLE (-75 3550);
FORCEPROP 2 LAST CDS_LIB pure_quanta
J 0
(-125 3375);
DISPLAY INVISIBLE (-125 3375);
FORCEPROP 0 LAST $SEC 1
J 0
(-75 3550);
DISPLAY 0.680851 (-75 3550);
PAINT MONO (-75 3550);
DISPLAY INVISIBLE (-75 3550);
FORCEPROP 0 LAST CDS_SEC 1
J 0
(-75 3550);
DISPLAY 1.021277 (-75 3550);
DISPLAY INVISIBLE (-75 3550);
FORCEADD Q_RES..1
(-150 -200);
FORCEPROP 1 LAST PART_NUMBER CS03322FB03
J 0
(-275 -150);
DISPLAY 0.638298 (-275 -150);
DISPLAY INVISIBLE (-275 -150);
FORCEPROP 1 LAST VALUE 33.2
J 2
(25 -200);
DISPLAY 0.638298 (25 -200);
FORCEPROP 1 LAST MATERIAL CHIP
J 0
(-275 -100);
DISPLAY 0.638298 (-275 -100);
FORCEPROP 1 LAST WATTAGE 1/16W
J 2
(50 -100);
DISPLAY 0.638298 (50 -100);
FORCEPROP 1 LAST PACK_TYPE 0402LF
J 0
(150 -200);
DISPLAY 0.638298 (150 -200);
FORCEPROP 1 LAST TOLERANCE 1%
J 0
(50 -200);
DISPLAY 0.638298 (50 -200);
FORCEPROP 1 LAST LOCATION R1736
J 0
(-375 -200);
DISPLAY 0.510638 (-375 -200);
FORCEPROP 1 LASTPIN (-250 -200) $PN 1
J 0
(-238 -188);
DISPLAY 0.787234 (-238 -188);
PAINT MONO (-238 -188);
FORCEPROP 1 LASTPIN (-50 -200) $PN 2
J 0
(-88 -188);
DISPLAY 0.787234 (-88 -188);
PAINT MONO (-88 -188);
FORCEPROP 1 LAST PATH I99
J 0
(-200 -50);
DISPLAY 0.978723 (-200 -50);
PAINT WHITE (-200 -50);
DISPLAY INVISIBLE (-200 -50);
FORCEPROP 2 LAST CDS_LIB pure_quanta
J 0
(-150 -200);
DISPLAY INVISIBLE (-150 -200);
FORCEPROP 0 LAST $SEC 1
J 0
(50 -50);
DISPLAY 0.680851 (50 -50);
PAINT MONO (50 -50);
DISPLAY INVISIBLE (50 -50);
FORCEPROP 0 LAST CDS_SEC 1
J 0
(50 -50);
DISPLAY 1.021277 (50 -50);
DISPLAY INVISIBLE (50 -50);
FORCEADD DNS..2
(-1120 2770);
PAINT RED (-1120 2770);
FORCEPROP 1 LAST COMMENT_BODY TRUE
J 0
(-1120 2770);
DISPLAY INVISIBLE (-1120 2770);
FORCEPROP 2 LAST CDS_LIB mstr_misc
J 0
(-1120 2770);
PAINT MONO (-1120 2770);
DISPLAY INVISIBLE (-1120 2770);
FORCEADD DNS..2
(-95 1470);
PAINT RED (-95 1470);
FORCEPROP 1 LAST COMMENT_BODY TRUE
J 0
(-95 1470);
DISPLAY INVISIBLE (-95 1470);
FORCEPROP 2 LAST CDS_LIB mstr_misc
J 0
(-95 1470);
PAINT MONO (-95 1470);
DISPLAY INVISIBLE (-95 1470);
FORCEADD DNS..2
(3875 -600);
PAINT RED (3875 -600);
FORCEPROP 1 LAST COMMENT_BODY TRUE
J 0
(3875 -600);
DISPLAY INVISIBLE (3875 -600);
FORCEPROP 2 LAST CDS_LIB mstr_misc
J 0
(3875 -600);
DISPLAY INVISIBLE (3875 -600);
FORCEADD DNS..2
(5130 595);
PAINT RED (5130 595);
FORCEPROP 2 LAST CDS_LIB mstr_misc
J 0
(5130 595);
PAINT MONO (5130 595);
DISPLAY INVISIBLE (5130 595);
FORCEPROP 1 LAST COMMENT_BODY TRUE
J 0
(5130 595);
DISPLAY INVISIBLE (5130 595);
FORCEADD DNS..2
(5405 595);
PAINT RED (5405 595);
FORCEPROP 2 LAST CDS_LIB mstr_misc
J 0
(5405 595);
PAINT MONO (5405 595);
DISPLAY INVISIBLE (5405 595);
FORCEPROP 1 LAST COMMENT_BODY TRUE
J 0
(5405 595);
DISPLAY INVISIBLE (5405 595);
FORCEADD QUANTA_TITLE_BLOCK_C..1
(6425 -2450);
FORCEPROP 0 LAST CDS_CON_LAST_MODIFIED Fri Aug 25 14:02:54 2023
J 0
(4540 -2435);
PAINT MONO (4540 -2435);
DISPLAY INVISIBLE (4540 -2435);
FORCEPROP 2 LAST CUSTOM_TXT_CDS <XR_PAGE_TITLE>
J 0
(-1465 2800);
DISPLAY 0.638298 (-1465 2800);
PAINT PINK (-1465 2800);
DISPLAY INVISIBLE (-1465 2800);
FORCEPROP 2 LAST CUSTOM_TXT_CDS <Q_NUMBER>
J 0
(5022 -2347);
DISPLAY 1.212766 (5022 -2347);
FORCEPROP 2 LAST CUSTOM_TXT_CDS <CON_PAGE_NUM> OF <CON_TOTAL_PAGES>
J 0
(5979 -2432);
DISPLAY 0.978723 (5979 -2432);
FORCEPROP 2 LAST CUSTOM_TXT_CDS <Q_REV>
J 0
(6241 -2347);
DISPLAY 1.212766 (6241 -2347);
FORCEPROP 2 LAST CUSTOM_TXT_CDS <CON_LAST_MODIFIED>
J 0
(4540 -2435);
DISPLAY 0.978723 (4540 -2435);
FORCEPROP 2 LAST CUSTOM_TXT_CDS <NAME_2>
J 0
(3250 -2400);
FORCEPROP 2 LAST CUSTOM_TXT_CDS <NAME_1>
J 0
(3250 -2275);
FORCEPROP 2 LAST CUSTOM_TXT_CDS <Q_PROJ>
J 0
(4043 -2348);
DISPLAY 1.212766 (4043 -2348);
FORCEPROP 1 LAST Q_TITLE EMMITSBURG - GPIO/JTAG (4/10)
J 0
(-2891 -2424);
DISPLAY 1.957447 (-2891 -2424);
PAINT GREEN (-2891 -2424);
FORCEPROP 1 LAST Q_DEPT 
J 1
(2662 -2401);
DISPLAY 1.957447 (2662 -2401);
PAINT GREEN (2662 -2401);
FORCEPROP 2 LAST CDS_XR_PAGE_TITLE CR-182 : @S9S_MB_2U_LIB.S9S_MB_2U(SCH_1):PAGE182
J 0
(-1465 2800);
DISPLAY 0.638298 (-1465 2800);
PAINT PINK (-1465 2800);
DISPLAY INVISIBLE (-1465 2800);
FORCEPROP 2 LAST CDS_LIB pure_quanta
J 0
(6425 -2450);
PAINT MONO (6425 -2450);
DISPLAY INVISIBLE (6425 -2450);
FORCEPROP 1 LAST CDS_LMAN_SYM_OUTLINE -9475,6775,100,-125
J 0
(6425 -2450);
DISPLAY 0.468085 (6425 -2450);
PAINT GREEN (6425 -2450);
DISPLAY INVISIBLE (6425 -2450);
FORCEPROP 2 LAST PAGE_BORDER TRUE
J 0
(-1465 2800);
DISPLAY 0.638298 (-1465 2800);
PAINT PINK (-1465 2800);
DISPLAY INVISIBLE (-1465 2800);
FORCEPROP 1 LAST COMMENT_BODY TRUE
J 0
(6437 -2463);
DISPLAY 0.978723 (6437 -2463);
PAINT GREEN (6437 -2463);
DISPLAY INVISIBLE (6437 -2463);
WIRE 16 -1 (-125 3575)(-125 3650);
WIRE 16 -1 (-250 3575)(-125 3575);
WIRE 16 -1 (-125 3475)(-125 3575);
WIRE 16 -1 (5125 800)(5125 775);
WIRE 16 -1 (1200 1275)(1200 1375);
WIRE 16 -1 (525 1275)(1200 1275);
WIRE 16 -1 (-2150 2425)(-2150 2475);
WIRE 16 -1 (-1950 2425)(-2150 2425);
WIRE 16 -1 (-1675 2475)(-1675 2550);
WIRE 16 -1 (-1475 2475)(-1675 2475);
WIRE 16 -1 (4450 -200)(4450 -350);
WIRE 16 -1 (5025 2550)(5025 2700);
WIRE 16 -1 (-100 1400)(-100 1275);
WIRE 16 -1 (-250 1400)(-250 1275);
WIRE 16 -1 (-1425 2725)(-1425 2775);
WIRE 16 -1 (4450 -675)(4450 -600);
WIRE 16 -1 (-1500 -200)(-250 -200);
FORCEPROP 0 LAST CDS_PHYS_NET_NAME FM_PCH_SLP_S4_N
J 0
(-1475 -158);
PAINT MONO (-1475 -158);
DISPLAY INVISIBLE (-1475 -158);
FORCEPROP 0 LAST SIG_NAME FM_PCH_SLP_SUS_N
J 0
(-1175 -190);
DISPLAY 0.553191 (-1175 -190);
PAINT WHITE (-1175 -190);
WIRE 16 2175 (-500 -50)(375 -50);
WIRE 16 2175 (375 -50)(375 -275);
WIRE 16 2175 (-500 -50)(-500 -275);
WIRE 16 2175 (-500 -275)(375 -275);
WIRE 16 -1 (-50 -200)(1200 -200);
FORCEPROP 0 LAST CDS_PHYS_NET_NAME FM_PCH_SLP_S4_N
J 0
(-25 -158);
PAINT MONO (-25 -158);
DISPLAY INVISIBLE (-25 -158);
FORCEPROP 0 LAST SIG_NAME FM_SLP_SUS_RSM_RST_N
J 0
(500 -190);
DISPLAY 0.553191 (500 -190);
PAINT WHITE (500 -190);
WIRE 16 -1 (-50 375)(1200 375);
FORCEPROP 0 LAST CDS_PHYS_NET_NAME FM_SLPS3_GF_N
J 0
(-25 417);
PAINT MONO (-25 417);
DISPLAY INVISIBLE (-25 417);
FORCEPROP 0 LAST SIG_NAME RST_PCH_RSTBTN_R_N
J 0
(500 385);
DISPLAY 0.553191 (500 385);
PAINT WHITE (500 385);
WIRE 16 -1 (-1500 375)(-250 375);
FORCEPROP 0 LAST CDS_PHYS_NET_NAME FM_PCH_SLP_S3_N
J 0
(-1475 417);
PAINT MONO (-1475 417);
DISPLAY INVISIBLE (-1475 417);
FORCEPROP 0 LAST SIG_NAME FM_BMC_RSTBTN_OUT_N
J 0
(-1175 385);
DISPLAY 0.553191 (-1175 385);
PAINT WHITE (-1175 385);
WIRE 16 -1 (3575 -600)(3750 -600);
WIRE 16 -1 (3575 -350)(3575 -600);
WIRE 16 -1 (3575 -350)(3750 -350);
WIRE 16 -1 (2500 -350)(3575 -350);
FORCEPROP 0 LAST CDS_PHYS_NET_NAME FM_PCH_SLP_S4_N
J 0
(2525 -308);
PAINT MONO (2525 -308);
DISPLAY INVISIBLE (2525 -308);
FORCEPROP 0 LAST SIG_NAME FM_PCIE_EV_BIF_EN
J 0
(2775 -340);
DISPLAY 0.553191 (2775 -340);
PAINT WHITE (2775 -340);
WIRE 16 -1 (3950 350)(5125 350);
FORCEPROP 0 LAST CDS_PHYS_NET_NAME FM_PCH_SLP_S4_N
J 0
(3975 392);
PAINT MONO (3975 392);
DISPLAY INVISIBLE (3975 392);
FORCEPROP 0 LAST SIG_NAME FM_PCH_TRIGGER0_R_N
J 0
(4500 360);
DISPLAY 0.553191 (4500 360);
PAINT WHITE (4500 360);
WIRE 16 -1 (5125 350)(5550 350);
WIRE 16 -1 (5125 500)(5125 350);
WIRE 16 -1 (3950 100)(5400 100);
FORCEPROP 0 LAST CDS_PHYS_NET_NAME FM_PCH_SLP_S4_N
J 0
(3975 142);
PAINT MONO (3975 142);
DISPLAY INVISIBLE (3975 142);
FORCEPROP 0 LAST SIG_NAME FM_PCH_TRIGGER1_R_N
J 0
(4500 110);
DISPLAY 0.553191 (4500 110);
PAINT WHITE (4500 110);
WIRE 16 -1 (5400 100)(5550 100);
WIRE 16 -1 (5400 500)(5400 100);
WIRE 16 -1 (2500 100)(3750 100);
FORCEPROP 0 LAST CDS_PHYS_NET_NAME FM_PCH_SLP_S4_N
J 0
(2525 142);
PAINT MONO (2525 142);
DISPLAY INVISIBLE (2525 142);
FORCEPROP 0 LAST SIG_NAME FM_PCH_TRIGGER1_N
J 0
(2775 110);
DISPLAY 0.553191 (2775 110);
PAINT WHITE (2775 110);
WIRE 16 -1 (2500 350)(3750 350);
FORCEPROP 0 LAST CDS_PHYS_NET_NAME FM_PCH_SLP_S4_N
J 0
(2525 392);
PAINT MONO (2525 392);
DISPLAY INVISIBLE (2525 392);
FORCEPROP 0 LAST SIG_NAME FM_PCH_TRIGGER0_N
J 0
(2775 360);
DISPLAY 0.553191 (2775 360);
PAINT WHITE (2775 360);
WIRE 16 -1 (4150 2675)(3125 2675);
FORCEPROP 2 LAST SIG_NAME FM_PCH_TRIGGER1_R_N
J 0
(3340 2685);
DISPLAY 0.553191 (3340 2685);
PAINT WHITE (3340 2685);
WIRE 16 -1 (4150 2625)(3125 2625);
FORCEPROP 2 LAST SIG_NAME FM_PCH_TRIGGER0_R_N
J 0
(3340 2635);
DISPLAY 0.553191 (3340 2635);
PAINT WHITE (3340 2635);
WIRE 16 -1 (4150 2575)(3125 2575);
FORCEPROP 2 LAST SIG_NAME TP_PLTRST_N
J 0
(3340 2585);
DISPLAY 0.553191 (3340 2585);
PAINT WHITE (3340 2585);
WIRE 16 -1 (4150 2375)(3125 2375);
FORCEPROP 2 LAST SIG_NAME RST_RSMRST_PCH_N
J 0
(3340 2385);
DISPLAY 0.553191 (3340 2385);
PAINT WHITE (3340 2385);
WIRE 16 -1 (4150 2925)(3125 2925);
FORCEPROP 2 LAST SIG_NAME PECI_PCH
J 0
(3340 2935);
DISPLAY 0.553191 (3340 2935);
PAINT WHITE (3340 2935);
WIRE 16 -1 (4150 2825)(3125 2825);
FORCEPROP 2 LAST SIG_NAME TP_PCH_CPU_MSMI_N
J 0
(3340 2835);
DISPLAY 0.553191 (3340 2835);
PAINT WHITE (3340 2835);
WIRE 16 -1 (4150 2525)(3125 2525);
FORCEPROP 2 LAST SIG_NAME H_THERMTRIP_LVC1_N
J 0
(3340 2535);
DISPLAY 0.553191 (3340 2535);
PAINT WHITE (3340 2535);
WIRE 16 -1 (4150 2475)(3125 2475);
FORCEPROP 2 LAST SIG_NAME PWRGD_CPUPWRGD_GTL
J 0
(3340 2485);
DISPLAY 0.553191 (3340 2485);
PAINT WHITE (3340 2485);
WIRE 16 -1 (4150 2975)(3125 2975);
FORCEPROP 2 LAST SIG_NAME H_CPU_ERR0_PCH_R_N
J 0
(3340 2985);
DISPLAY 0.553191 (3340 2985);
PAINT WHITE (3340 2985);
WIRE 16 -1 (4150 3025)(3125 3025);
FORCEPROP 2 LAST SIG_NAME H_CPU_ERR1_PCH_R_N
J 0
(3340 3035);
DISPLAY 0.553191 (3340 3035);
PAINT WHITE (3340 3035);
WIRE 16 -1 (4150 3075)(3125 3075);
FORCEPROP 2 LAST SIG_NAME H_CPU_ERR2_PCH_R_N
J 0
(3340 3085);
DISPLAY 0.553191 (3340 3085);
PAINT WHITE (3340 3085);
WIRE 16 -1 (4150 3125)(3125 3125);
FORCEPROP 2 LAST SIG_NAME FM_PCIE_EV_BIF_EN
J 0
(3340 3135);
DISPLAY 0.553191 (3340 3135);
PAINT WHITE (3340 3135);
WIRE 16 -1 (4150 2325)(3125 2325);
FORCEPROP 2 LAST SIG_NAME PWRGD_PCH_PWROK
J 0
(3340 2335);
DISPLAY 0.553191 (3340 2335);
PAINT WHITE (3340 2335);
WIRE 16 -1 (4150 2275)(3125 2275);
FORCEPROP 2 LAST SIG_NAME PWRGD_DSW_PWROK
J 0
(3340 2285);
DISPLAY 0.553191 (3340 2285);
PAINT WHITE (3340 2285);
WIRE 16 -1 (3125 2225)(5025 2225);
FORCEPROP 2 LAST SIG_NAME FM_INTRUDER_HDR_PCH_N
J 0
(3340 2235);
DISPLAY 0.553191 (3340 2235);
PAINT WHITE (3340 2235);
WIRE 16 -1 (5025 2225)(5025 2350);
WIRE 16 -1 (-250 2275)(-375 2275);
WIRE 16 -1 (875 2275)(-250 2275);
FORCEPROP 2 LAST SIG_NAME JTAG_DBP_TCK_PCH
J 0
(-50 2285);
DISPLAY 0.553191 (-50 2285);
PAINT WHITE (-50 2285);
WIRE 16 -1 (-250 1600)(-250 2275);
WIRE 16 -1 (-100 2075)(-100 1600);
WIRE 16 -1 (-375 2075)(-100 2075);
WIRE 16 -1 (875 2075)(-100 2075);
FORCEPROP 2 LAST SIG_NAME JTAG_DBP_CPU_GTL_TCK
J 0
(-50 2085);
DISPLAY 0.553191 (-50 2085);
PAINT WHITE (-50 2085);
WIRE 16 -1 (4150 2125)(3125 2125);
FORCEPROP 2 LAST SIG_NAME NC_PCH_RSVD<3>
J 0
(3340 2135);
DISPLAY 0.553191 (3340 2135);
PAINT WHITE (3340 2135);
WIRE 16 -1 (4150 2075)(3125 2075);
FORCEPROP 2 LAST SIG_NAME NC_PCH_RSVD<4>
J 0
(3340 2085);
DISPLAY 0.553191 (3340 2085);
PAINT WHITE (3340 2085);
WIRE 16 -1 (4150 1975)(3125 1975);
FORCEPROP 2 LAST SIG_NAME NC_PCH_RSVD<5>
J 0
(3340 1985);
DISPLAY 0.553191 (3340 1985);
PAINT WHITE (3340 1985);
WIRE 16 -1 (4150 1925)(3125 1925);
FORCEPROP 2 LAST SIG_NAME NC_PCH_RSVD<17>
J 0
(3340 1935);
DISPLAY 0.553191 (3340 1935);
PAINT WHITE (3340 1935);
WIRE 16 -1 (875 2375)(-375 2375);
FORCEPROP 2 LAST SIG_NAME FM_PCH_SPARE0
J 0
(-50 2385);
DISPLAY 0.553191 (-50 2385);
PAINT WHITE (-50 2385);
WIRE 16 -1 (875 2425)(-1750 2425);
FORCEPROP 2 LAST SIG_NAME PU_ACPRESENT
J 0
(-50 2435);
DISPLAY 0.553191 (-50 2435);
PAINT WHITE (-50 2435);
WIRE 16 -1 (525 1400)(525 1275);
WIRE 16 -1 (5125 775)(5125 700);
WIRE 16 -1 (5400 775)(5125 775);
WIRE 16 -1 (5400 700)(5400 775);
WIRE 16 -1 (-1425 2775)(-1225 2775);
WIRE 16 -1 (4450 -350)(3950 -350);
WIRE 16 -1 (4450 -600)(3950 -600);
WIRE 16 -1 (875 1975)(-375 1975);
FORCEPROP 2 LAST SIG_NAME H_DBP_PREQ_N_PCH
J 0
(-50 1985);
DISPLAY 0.553191 (-50 1985);
PAINT WHITE (-50 1985);
WIRE 16 -1 (875 1925)(-375 1925);
FORCEPROP 2 LAST SIG_NAME H_DBP_PRDY_N_PCH
J 0
(-50 1935);
DISPLAY 0.553191 (-50 1935);
PAINT WHITE (-50 1935);
WIRE 16 -1 (525 1600)(525 1825);
WIRE 16 -1 (525 1825)(875 1825);
WIRE 16 -1 (-375 1825)(525 1825);
FORCEPROP 2 LAST SIG_NAME JTAG_DBP_PMODE
J 0
(-50 1835);
DISPLAY 0.553191 (-50 1835);
PAINT WHITE (-50 1835);
WIRE 16 -1 (4150 2775)(3125 2775);
FORCEPROP 2 LAST SIG_NAME TP_PCH_CPU_MEMTRIP_N
J 0
(3340 2785);
DISPLAY 0.553191 (3340 2785);
PAINT WHITE (3340 2785);
WIRE 16 -1 (4150 2725)(3125 2725);
FORCEPROP 2 LAST SIG_NAME FM_PCH_CPU_PWR_DEBUG_N
J 0
(3340 2735);
DISPLAY 0.553191 (3340 2735);
PAINT WHITE (3340 2735);
WIRE 16 -1 (875 2125)(-375 2125);
FORCEPROP 2 LAST SIG_NAME JTAG_DBP_TMS_PCH
J 0
(-50 2135);
DISPLAY 0.553191 (-50 2135);
PAINT WHITE (-50 2135);
WIRE 16 -1 (875 2175)(-375 2175);
FORCEPROP 2 LAST SIG_NAME JTAG_DBP_TDO_PCH
J 0
(-50 2185);
DISPLAY 0.553191 (-50 2185);
PAINT WHITE (-50 2185);
WIRE 16 -1 (875 2225)(-375 2225);
FORCEPROP 2 LAST SIG_NAME JTAG_DBP_TDI_PCH
J 0
(-50 2235);
DISPLAY 0.553191 (-50 2235);
PAINT WHITE (-50 2235);
WIRE 16 -1 (-375 3025)(875 3025);
FORCEPROP 0 LAST SIG_NAME TP_SLP_LAN_N
J 0
(-50 3035);
DISPLAY 0.553191 (-50 3035);
PAINT WHITE (-50 3035);
WIRE 16 -1 (-375 3125)(875 3125);
FORCEPROP 0 LAST SIG_NAME FM_PCH_SLP_SUS_N
J 0
(-50 3135);
DISPLAY 0.553191 (-50 3135);
PAINT WHITE (-50 3135);
WIRE 16 -1 (-250 3475)(-250 3575);
WIRE 16 -1 (-125 3275)(-125 3075);
WIRE 16 -1 (875 3075)(-125 3075);
FORCEPROP 0 LAST SIG_NAME IRQ_LVC3_WAKE_N
J 0
(-50 3085);
DISPLAY 0.553191 (-50 3085);
PAINT WHITE (-50 3085);
WIRE 16 -1 (-375 3075)(-125 3075);
WIRE 16 2175 (-175 3550)(175 3550);
WIRE 16 2175 (175 3550)(175 3175);
WIRE 16 2175 (-175 3550)(-175 3175);
WIRE 16 2175 (-175 3175)(175 3175);
WIRE 16 -1 (-250 3275)(-250 2975);
WIRE 16 -1 (-250 2975)(875 2975);
FORCEPROP 0 LAST SIG_NAME RST_PCH_RSTBTN_R_N
J 0
(-50 2985);
DISPLAY 0.553191 (-50 2985);
PAINT WHITE (-50 2985);
WIRE 16 -1 (-375 2975)(-250 2975);
WIRE 16 -1 (-375 2925)(875 2925);
FORCEPROP 0 LAST SIG_NAME PWRGD_SYS_PWROK
J 0
(-50 2935);
DISPLAY 0.553191 (-50 2935);
PAINT WHITE (-50 2935);
WIRE 16 -1 (-250 2675)(875 2675);
FORCEPROP 0 LAST CDS_PHYS_NET_NAME FM_PCH_SLP_S4_N
J 0
(-225 2717);
PAINT MONO (-225 2717);
DISPLAY INVISIBLE (-225 2717);
FORCEPROP 0 LAST SIG_NAME TP_PCH_SLP_A_N
J 0
(-50 2685);
DISPLAY 0.553191 (-50 2685);
PAINT WHITE (-50 2685);
WIRE 16 -1 (-375 2625)(875 2625);
FORCEPROP 0 LAST CDS_PHYS_NET_NAME FM_PCH_SLP_S4_N
J 0
(-350 2667);
PAINT MONO (-350 2667);
DISPLAY INVISIBLE (-350 2667);
FORCEPROP 0 LAST SIG_NAME FM_PCH_SLP_S4_N
J 0
(-50 2635);
DISPLAY 0.553191 (-50 2635);
PAINT WHITE (-50 2635);
WIRE 16 -1 (-375 2575)(875 2575);
FORCEPROP 0 LAST CDS_PHYS_NET_NAME FM_PCH_SLP_S4_N
J 0
(-350 2617);
PAINT MONO (-350 2617);
DISPLAY INVISIBLE (-350 2617);
FORCEPROP 0 LAST SIG_NAME FM_PCH_SLP_S3_N
J 0
(-50 2585);
DISPLAY 0.553191 (-50 2585);
PAINT WHITE (-50 2585);
WIRE 16 -1 (-375 2525)(875 2525);
FORCEPROP 0 LAST SIG_NAME FM_BMC_PWRBTN_N
J 0
(-50 2535);
DISPLAY 0.553191 (-50 2535);
PAINT WHITE (-50 2535);
WIRE 16 -1 (875 2475)(-1275 2475);
FORCEPROP 0 LAST SIG_NAME PU_LAN_WAKE_N
J 0
(-60 2485);
DISPLAY 0.553191 (-60 2485);
PAINT WHITE (-60 2485);
WIRE 16 -1 (-375 2725)(875 2725);
FORCEPROP 0 LAST CDS_PHYS_NET_NAME FM_PCH_SLP_S4_N
J 0
(-350 2767);
PAINT MONO (-350 2767);
DISPLAY INVISIBLE (-350 2767);
FORCEPROP 0 LAST SIG_NAME FM_PCH_SKIP_RTC_CLOCK
J 0
(-50 2735);
DISPLAY 0.553191 (-50 2735);
PAINT WHITE (-50 2735);
WIRE 16 -1 (875 2775)(-1025 2775);
FORCEPROP 0 LAST CDS_PHYS_NET_NAME CLK_33K_PCH_SUSCLK_PLD
J 0
(-250 2817);
PAINT MONO (-250 2817);
DISPLAY INVISIBLE (-250 2817);
FORCEPROP 0 LAST SIG_NAME PD_SUSCLK
J 0
(-50 2785);
DISPLAY 0.553191 (-50 2785);
PAINT WHITE (-50 2785);
WIRE 16 -1 (-250 2825)(875 2825);
FORCEPROP 0 LAST CDS_PHYS_NET_NAME FM_PCH_SLP_S4_N
J 0
(-225 2867);
PAINT MONO (-225 2867);
DISPLAY INVISIBLE (-225 2867);
FORCEPROP 0 LAST SIG_NAME TP_PCH_SLP_S5_N
J 0
(-50 2835);
DISPLAY 0.553191 (-50 2835);
PAINT WHITE (-50 2835);
WIRE 16 -1 (-250 2875)(875 2875);
FORCEPROP 0 LAST CDS_PHYS_NET_NAME FM_PCH_SLP_S4_N
J 0
(-225 2917);
PAINT MONO (-225 2917);
DISPLAY INVISIBLE (-225 2917);
FORCEPROP 0 LAST SIG_NAME TP_PCH_GPP_O_11
J 0
(-50 2885);
DISPLAY 0.553191 (-50 2885);
PAINT WHITE (-50 2885);
DOT 1 (5125 350);
DOT 1 (5125 775);
DOT 1 (3575 -350);
DOT 1 (-100 2075);
DOT 1 (5400 100);
DOT 1 (-250 2275);
DOT 1 (-125 3575);
DOT 1 (525 1825);
DOT 1 (-125 3075);
DOT 1 (-250 2975);
FORCENOTE
20210630 MODIFY FOR GT
(3475 1500) 0;
DISPLAY LEFT (3475 1500);
DISPLAY 1.595745 (3475 1500);
PAINT PINK (3475 1500);
FORCENOTE
20211116 MODIFY FOR GT
(-925 3875) 0;
DISPLAY LEFT (-925 3875);
DISPLAY 1.595745 (-925 3875);
PAINT PINK (-925 3875);
FORCENOTE
20220725 CHANGE R1736 TO 33.2 OHM
(-750 -375) 0;
DISPLAY LEFT (-750 -375);
DISPLAY 1.276596 (-750 -375);
PAINT PINK (-750 -375);
QUIT
